# Altium SchDoc records: PCIe_JTAG.SchDoc
|HEADER=Protel for Windows - Schematic Capture Binary File Version 5.0|Weight=1166|MinorVersion=4
|RECORD=31|FontIdCount=9|Size1=10|FontName1=Times New Roman|Size2=8|FontName2=Arial|Size3=10|FontName3=Arial|Size4=12|Underline4=T|FontName4=Arial|Size5=24|FontName5=Times New Roman|Size6=11|FontName6=Arial|Size7=12|FontName7=Arial|Size8=7|FontName8=Arial|Size9=7|FontName9=Courier New|UseMBCS=T|IsBOC=T|HotSpotGridOn=T|HotSpotGridSize_Frac=40000|SheetStyle=12|SystemFont=3|BorderOn=T|SheetNumberSpaceSize=12|AreaColor=16317695|SnapGridOn=T|SnapGridSize=1|VisibleGridOn=T|VisibleGridSize=10|CustomX=2338|CustomX_Frac=58268|CustomY=1653|CustomY_Frac=54331|CustomXZones=8|CustomYZones=6|CustomMarginWidth=19|CustomMarginWidth_Frac=80000|ShowTemplateGraphics=T|TemplateFileName=C:\Users\<user>\Documents\Altium\AD20\Templates\Timecard.SchDot|Display_Unit=0
|RECORD=39|IsNotAccesible=T|OwnerPartId=-1|FileName=C:\Users\<user>\Documents\Altium\AD20\Templates\Timecard.SchDot
|RECORD=4|OwnerIndex=1|OwnerPartId=-1|Location.X=1594|Location.Y=39|Color=8388608|FontID=4|Text=timingcard.com|URL=http://timingcard.com
|RECORD=6|OwnerIndex=1|IndexInSheet=1|OwnerPartId=-1|LocationCount=2|X1=1680|Y1=35|X2=1576|Y2=35
|RECORD=4|OwnerIndex=1|IndexInSheet=2|OwnerPartId=-1|Location.X=1615|Location.Y=27|Justification=4|Color=16711680|FontID=6|Text==SheetNumber
|RECORD=4|OwnerIndex=1|IndexInSheet=3|OwnerPartId=-1|Location.X=1581|Location.X_Frac=42446|Location.Y=29|Location.Y_Frac=96838|Justification=3|FontID=2|Text=SHEET
|RECORD=4|OwnerIndex=1|IndexInSheet=4|OwnerPartId=-1|Location.X=1639|Location.X_Frac=42446|Location.Y=29|Location.Y_Frac=96838|Justification=3|FontID=2|Text=OF
|RECORD=6|OwnerIndex=1|IndexInSheet=5|OwnerPartId=-1|LineWidth=1|LocationCount=2|X1=1679|X1_Frac=42446|Y1=117|Y1_Frac=96838|X2=1576|Y2=118
|RECORD=4|OwnerIndex=1|IndexInSheet=6|OwnerPartId=-1|Location.X=1659|Location.Y=27|Justification=4|Color=16711680|FontID=6|Text==SheetTotal
|RECORD=30|OwnerIndex=1|IndexInSheet=7|OwnerPartId=-1|Location.X=1578|Location.Y=65|Corner.X=1673|Corner.X_Frac=88801|Corner.Y=115|KeepAspect=T|FileName=C:\Users\<user>\Desktop\Timecard Logo\TIMECARD.jpg
|RECORD=6|OwnerIndex=1|IndexInSheet=8|OwnerPartId=-1|LineWidth=1|LocationCount=2|X1=1576|X1_Frac=3162|Y1=117|Y1_Frac=42446|X2=1576|Y2=21
|RECORD=6|OwnerIndex=1|IndexInSheet=9|OwnerPartId=-1|LocationCount=2|X1=1680|Y1=51|X2=1576|Y2=51
|RECORD=4|OwnerIndex=1|IndexInSheet=10|OwnerPartId=-1|Location.X=1581|Location.X_Frac=42446|Location.Y=56|Location.Y_Frac=96838|Justification=3|FontID=2|Text=REV
|RECORD=4|OwnerIndex=1|IndexInSheet=11|OwnerPartId=-1|Location.X=1619|Location.Y=57|Justification=3|FontID=2|Text=DATE
|RECORD=6|OwnerIndex=1|IndexInSheet=12|OwnerPartId=-1|LocationCount=2|X1=1680|Y1=65|X2=1576|Y2=65
|RECORD=4|OwnerIndex=1|IndexInSheet=13|OwnerPartId=-1|Location.X=1605|Location.Y=58|Justification=4|Color=16711680|FontID=6|Text==ProjectRevision
|RECORD=4|OwnerIndex=1|IndexInSheet=14|OwnerPartId=-1|Location.X=1659|Location.Y=58|Justification=4|Color=16711680|FontID=6|Text==ProjectDate
|RECORD=41|IndexInSheet=1|OwnerPartId=-1|Location.X=21474|Location.X_Frac=83647|Location.Y=21464|Location.Y_Frac=83647|Color=8388608|FontID=1|IsHidden=T|Text=01910|Name=Customer
|RECORD=41|IndexInSheet=2|OwnerPartId=-1|Location.X=1000|Location.Y=10|Color=8388608|FontID=1|IsHidden=T|Text=*|Name=DocStatus
|RECORD=17|IndexInSheet=3|OwnerPartId=-1|Style=4|ShowNetName=T|Location.X=740|Location.Y=600|Orientation=3|Color=128|FontID=1|Text=GND
|RECORD=17|IndexInSheet=4|OwnerPartId=-1|Style=4|ShowNetName=T|Location.X=940|Location.Y=600|Orientation=3|Color=128|FontID=1|Text=GND
|RECORD=17|IndexInSheet=5|OwnerPartId=-1|ShowNetName=T|Location.X=670|Location.Y=970|Orientation=1|Color=128|FontID=1|Text=+12V_PCIE
|RECORD=17|IndexInSheet=6|OwnerPartId=-1|ShowNetName=T|Location.X=540|Location.Y=970|Orientation=1|Color=128|FontID=1|Text=+3.3V_PCIE
|RECORD=17|IndexInSheet=7|OwnerPartId=-1|ShowNetName=T|Location.X=1060|Location.Y=920|Orientation=1|Color=128|FontID=1|Text=+3.3V
|RECORD=17|IndexInSheet=8|OwnerPartId=-1|ShowNetName=T|Location.X=1030|Location.Y=940|Orientation=1|Color=128|FontID=1|Text=+3.3V_PCIE
|RECORD=17|IndexInSheet=9|OwnerPartId=-1|ShowNetName=T|Location.X=990|Location.Y=970|Orientation=1|Color=128|FontID=1|Text=+12V_PCIE
|RECORD=22|IndexInSheet=10|OwnerPartId=-1|Location.X=760|Location.Y=910|Color=255|Orientation=1|Symbol=Thin Cross|IsActive=T|SuppressAll=T
|RECORD=22|IndexInSheet=11|OwnerPartId=-1|Location.X=760|Location.Y=900|Color=255|Orientation=1|Symbol=Thin Cross|IsActive=T|SuppressAll=T
|RECORD=22|IndexInSheet=12|OwnerPartId=-1|Location.X=760|Location.Y=850|Color=255|Orientation=1|Symbol=Thin Cross|IsActive=T|SuppressAll=T
|RECORD=17|IndexInSheet=13|OwnerPartId=-1|ShowNetName=T|Location.X=540|Location.Y=810|Orientation=2|Color=255|FontID=1|Text=PCIE_RX0_P|IsCrossSheetConnector=T
|RECORD=17|IndexInSheet=14|OwnerPartId=-1|ShowNetName=T|Location.X=540|Location.Y=800|Orientation=2|Color=255|FontID=1|Text=PCIE_RX0_N|IsCrossSheetConnector=T
|RECORD=17|IndexInSheet=15|OwnerPartId=-1|ShowNetName=T|Location.X=540|Location.Y=760|Orientation=2|Color=255|FontID=1|Text=PCIE_RX1_P|IsCrossSheetConnector=T
|RECORD=17|IndexInSheet=16|OwnerPartId=-1|ShowNetName=T|Location.X=540|Location.Y=750|Orientation=2|Color=255|FontID=1|Text=PCIE_RX1_N|IsCrossSheetConnector=T
|RECORD=17|IndexInSheet=17|OwnerPartId=-1|ShowNetName=T|Location.X=540|Location.Y=720|Orientation=2|Color=255|FontID=1|Text=PCIE_RX2_P|IsCrossSheetConnector=T
|RECORD=17|IndexInSheet=18|OwnerPartId=-1|ShowNetName=T|Location.X=540|Location.Y=710|Orientation=2|Color=255|FontID=1|Text=PCIE_RX2_N|IsCrossSheetConnector=T
|RECORD=17|IndexInSheet=19|OwnerPartId=-1|ShowNetName=T|Location.X=540|Location.Y=680|Orientation=2|Color=255|FontID=1|Text=PCIE_RX3_P|IsCrossSheetConnector=T
|RECORD=17|IndexInSheet=20|OwnerPartId=-1|ShowNetName=T|Location.X=540|Location.Y=670|Orientation=2|Color=255|FontID=1|Text=PCIE_RX3_N|IsCrossSheetConnector=T
|RECORD=17|IndexInSheet=21|OwnerPartId=-1|ShowNetName=T|Location.X=1190|Location.Y=850|Color=255|FontID=1|Text=PCIE_PERST|IsCrossSheetConnector=T
|RECORD=17|IndexInSheet=22|OwnerPartId=-1|ShowNetName=T|Location.X=1190|Location.Y=820|Color=255|FontID=1|Text=PCIE_CLK_P|IsCrossSheetConnector=T
|RECORD=17|IndexInSheet=23|OwnerPartId=-1|ShowNetName=T|Location.X=1190|Location.Y=810|Color=255|FontID=1|Text=PCIE_CLK_N|IsCrossSheetConnector=T
|RECORD=17|IndexInSheet=24|OwnerPartId=-1|ShowNetName=T|Location.X=1190|Location.Y=790|Color=255|FontID=1|Text=PCIE_TX0_P|IsCrossSheetConnector=T
|RECORD=17|IndexInSheet=25|OwnerPartId=-1|ShowNetName=T|Location.X=1190|Location.Y=780|Color=255|FontID=1|Text=PCIE_TX0_N|IsCrossSheetConnector=T
|RECORD=17|IndexInSheet=26|OwnerPartId=-1|ShowNetName=T|Location.X=1190|Location.Y=740|Color=255|FontID=1|Text=PCIE_TX1_P|IsCrossSheetConnector=T
|RECORD=17|IndexInSheet=27|OwnerPartId=-1|ShowNetName=T|Location.X=1190|Location.Y=730|Color=255|FontID=1|Text=PCIE_TX1_N|IsCrossSheetConnector=T
|RECORD=17|IndexInSheet=28|OwnerPartId=-1|ShowNetName=T|Location.X=1190|Location.Y=700|Color=255|FontID=1|Text=PCIE_TX2_P|IsCrossSheetConnector=T
|RECORD=17|IndexInSheet=29|OwnerPartId=-1|ShowNetName=T|Location.X=1190|Location.Y=690|Color=255|FontID=1|Text=PCIE_TX2_N|IsCrossSheetConnector=T
|RECORD=17|IndexInSheet=30|OwnerPartId=-1|ShowNetName=T|Location.X=1190|Location.Y=660|Color=255|FontID=1|Text=PCIE_TX3_P|IsCrossSheetConnector=T
|RECORD=17|IndexInSheet=31|OwnerPartId=-1|ShowNetName=T|Location.X=1190|Location.Y=650|Color=255|FontID=1|Text=PCIE_TX3_N|IsCrossSheetConnector=T
|RECORD=4|IndexInSheet=32|OwnerPartId=-1|Location.X=800|Location.Y=1010|Color=8388608|FontID=5|Text=PCIe Connector
|RECORD=1|LibReference=RES_0603_4.7K|ComponentDescription=RES, 4.7K, 1%, 1/10W, TF, 0603|PartCount=2|DisplayModeCount=1|IndexInSheet=33|OwnerPartId=-1|Location.X=1060|Location.Y=860|Orientation=1|CurrentPartId=1|LibraryPath=*|SourceLibraryName=Resistors.IntLib|TargetFileName=*|AreaColor=11599871|Color=128|PartIDLocked=F|DesignItemId=RES_0603_4.7K|AllPinCount=2
|RECORD=41|OwnerIndex=49|OwnerPartId=-1|Location.X=1056|Location.Y=912|Color=8388608|FontID=7|IsHidden=T|Text=7/25/2013|Name=ModifyDate
|RECORD=41|OwnerIndex=49|IndexInSheet=1|OwnerPartId=-1|Location.X=1056|Location.Y=912|Color=8388608|FontID=7|IsHidden=T|Text=ERJ-3EKF4701V|Name=MFG PART NUM
|RECORD=41|OwnerIndex=49|IndexInSheet=2|OwnerPartId=-1|Location.X=1056|Location.Y=912|Color=8388608|FontID=7|IsHidden=T|Text=PANASONIC|Name=MFG NAME
|RECORD=41|OwnerIndex=49|IndexInSheet=3|OwnerPartId=-1|Location.X=1056|Location.Y=912|Color=8388608|FontID=7|IsHidden=T|Text=RES|Name=CATEGORY
|RECORD=41|OwnerIndex=49|IndexInSheet=4|OwnerPartId=-1|Location.X=1056|Location.Y=912|Color=8388608|FontID=7|IsHidden=T|Text=7/26/2013|Name=Date
|RECORD=41|OwnerIndex=49|IndexInSheet=5|OwnerPartId=-1|Location.X=1056|Location.Y=912|Color=8388608|FontID=7|IsHidden=T|Text=1%|Name=P1
|RECORD=41|OwnerIndex=49|IndexInSheet=6|OwnerPartId=-1|Location.X=1056|Location.Y=912|Color=8388608|FontID=7|IsHidden=T|Text=TF|Name=P3
|RECORD=41|OwnerIndex=49|IndexInSheet=7|OwnerPartId=-1|Location.X=1056|Location.Y=912|Color=8388608|FontID=7|IsHidden=T|Text=1/10W|Name=P2
|RECORD=41|OwnerIndex=49|IndexInSheet=8|OwnerPartId=-1|Location.X=1056|Location.Y=912|Color=8388608|FontID=7|IsHidden=T|Text=125C|Name=MAXTEMP
|RECORD=41|OwnerIndex=49|IndexInSheet=9|OwnerPartId=-1|Location.X=1056|Location.Y=912|Color=8388608|FontID=7|IsHidden=T|Text=-55C|Name=MINTEMP
|RECORD=41|OwnerIndex=49|IndexInSheet=10|OwnerPartId=-1|Location.X=1056|Location.Y=912|Color=8388608|FontID=7|IsHidden=T|Text=100PPM|Name=OTHER
|RECORD=41|OwnerIndex=49|IndexInSheet=11|OwnerPartId=-1|Location.X=1056|Location.Y=912|Color=8388608|FontID=7|IsHidden=T|Text=0603|Name=SIZE
|RECORD=41|OwnerIndex=49|IndexInSheet=12|OwnerPartId=-1|Location.X=1056|Location.Y=912|Color=8388608|FontID=7|IsHidden=T|Text=GENERIC|Name=SUB
|RECORD=41|OwnerIndex=49|IndexInSheet=13|OwnerPartId=-1|Location.X=1056|Location.Y=912|Color=8388608|FontID=7|IsHidden=T|Text=Digi-Key|Name=Supplier 1|ReadOnlyState=3
|RECORD=41|OwnerIndex=49|IndexInSheet=14|OwnerPartId=-1|Location.X=1056|Location.Y=912|Color=8388608|FontID=7|IsHidden=T|Text=P4.70KHCT-ND|Name=Supplier Part Number 1|ReadOnlyState=3
|RECORD=41|OwnerIndex=49|IndexInSheet=15|OwnerPartId=-1|Location.X=1056|Location.Y=912|Color=8388608|FontID=1|IsHidden=T|Text=*|Name=SHEETPART
|RECORD=41|OwnerIndex=49|IndexInSheet=16|OwnerPartId=-1|Location.X=1056|Location.Y=912|Color=8388608|FontID=1|IsHidden=T|Text=RES, 4.7K, 1%, 1/10W, TF, 0603|Name=DESC
|RECORD=41|OwnerIndex=49|IndexInSheet=17|OwnerPartId=-1|Location.X=1064|Location.Y=875|Color=8388608|FontID=7|Text=4.7K|Name=VALUE
|RECORD=2|OwnerIndex=49|OwnerPartId=1|FormalType=1|Electrical=4|PinConglomerate=35|PinLength=10|Location.X=1060|Location.Y=870|Name=1|Designator=1|PinPropagationDelay=0.000000E+000
|RECORD=2|OwnerIndex=49|OwnerPartId=1|FormalType=1|Electrical=4|PinConglomerate=33|PinLength=10|Location.X=1060|Location.Y=900|Name=2|Designator=2|PinPropagationDelay=0.000000E+000
|RECORD=6|OwnerIndex=49|IsNotAccesible=T|IndexInSheet=20|OwnerPartId=1|LineWidth=1|Color=16711680|LocationCount=7|X1=1060|Y1=900|X2=1057|Y2=897|X3=1063|Y3=891|X4=1057|Y4=885|X5=1063|Y5=879|X6=1057|Y6=873|X7=1060|Y7=870
|RECORD=41|OwnerIndex=49|IndexInSheet=21|OwnerPartId=-1|Location.X=1056|Location.Y=912|Color=8388608|FontID=1|IsHidden=T|Text=<VELENTIUM>|Name=VELENTIUM PART NUM
|RECORD=34|OwnerIndex=49|IndexInSheet=-1|OwnerPartId=-1|Location.X=1064|Location.Y=887|Color=8388608|FontID=1|Text=R22|Name=Designator|ReadOnlyState=1
|RECORD=41|OwnerIndex=49|IndexInSheet=-1|OwnerPartId=-1|Location.X=1056|Location.Y=912|Color=8388608|FontID=1|IsHidden=T|Text==MFG PART NUM|Name=Comment
|RECORD=44|OwnerIndex=49
|RECORD=45|OwnerIndex=76|IndexInSheet=-1|Description=Chip Resistor, 0603, 2-Leads, Body 1.57x0.85mm, IPC Medium Density|UseComponentLibrary=T|ModelName=RESC1608X50N|ModelType=PCBLIB|DatafileCount=1|ModelDatafileEntity0=RESC1608X50N|ModelDatafileKind0=PCBLib|IsCurrent=T|DatalinksLocked=T|DatabaseDatalinksLocked=T|IntegratedModel=T|DatabaseModel=T
|RECORD=46|OwnerIndex=77
|RECORD=48|OwnerIndex=77
|RECORD=1|LibReference=CAP_0402_0.1UF_50V|ComponentDescription=CAP, CER, 0.1UF, 50V, 10%, X7R, AEC-Q200, 0402|PartCount=2|DisplayModeCount=1|IndexInSheet=34|OwnerPartId=-1|Location.X=1130|Location.Y=630|Orientation=1|CurrentPartId=1|LibraryPath=*|SourceLibraryName=Capacitors.IntLib|TargetFileName=*|AreaColor=11599871|Color=128|PartIDLocked=F|DesignItemId=CAP_0402_0.1UF_50V|AllPinCount=2
|RECORD=41|OwnerIndex=80|OwnerPartId=-1|Location.X=1078|Location.Y=656|Color=8388608|FontID=7|IsHidden=T|Text=CAP, CER|Name=CATEGORY
|RECORD=41|OwnerIndex=80|IndexInSheet=1|OwnerPartId=-1|Location.X=1078|Location.Y=656|Color=8388608|FontID=7|IsHidden=T|Text=TDK|Name=MFG NAME
|RECORD=41|OwnerIndex=80|IndexInSheet=2|OwnerPartId=-1|Location.X=1078|Location.Y=656|Color=8388608|FontID=7|IsHidden=T|Text=CGA2B3X7R1H104K050BB|Name=MFG PART NUM
|RECORD=41|OwnerIndex=80|IndexInSheet=3|OwnerPartId=-1|Location.X=1078|Location.Y=656|Color=8388608|FontID=7|IsHidden=T|Text=10/23/2013|Name=MODIFY DATE
|RECORD=41|OwnerIndex=80|IndexInSheet=4|OwnerPartId=-1|Location.X=1078|Location.Y=656|Color=8388608|FontID=7|IsHidden=T|Name=Date
|RECORD=41|OwnerIndex=80|IndexInSheet=5|OwnerPartId=-1|Location.X=1078|Location.Y=656|Color=8388608|FontID=7|IsHidden=T|Text=*|Name=SHEETPART
|RECORD=41|OwnerIndex=80|IndexInSheet=6|OwnerPartId=-1|Location.X=1078|Location.Y=656|Color=8388608|FontID=7|IsHidden=T|Text=10%|Name=P1
|RECORD=41|OwnerIndex=80|IndexInSheet=7|OwnerPartId=-1|Location.X=1078|Location.Y=656|Color=8388608|FontID=7|IsHidden=T|Text=125C|Name=MAXTEMP
|RECORD=41|OwnerIndex=80|IndexInSheet=8|OwnerPartId=-1|Location.X=1078|Location.Y=656|Color=8388608|FontID=7|IsHidden=T|Text=-55C|Name=MINTEMP
|RECORD=41|OwnerIndex=80|IndexInSheet=9|OwnerPartId=-1|Location.X=1078|Location.Y=656|Color=8388608|FontID=7|IsHidden=T|Text=AEC-Q200|Name=OTHER
|RECORD=41|OwnerIndex=80|IndexInSheet=10|OwnerPartId=-1|Location.X=1078|Location.Y=656|Color=8388608|FontID=7|IsHidden=T|Text=50V|Name=P2
|RECORD=41|OwnerIndex=80|IndexInSheet=11|OwnerPartId=-1|Location.X=1078|Location.Y=656|Color=8388608|FontID=7|IsHidden=T|Text=X7R|Name=P3
|RECORD=41|OwnerIndex=80|IndexInSheet=12|OwnerPartId=-1|Location.X=1078|Location.Y=656|Color=8388608|FontID=7|IsHidden=T|Text=0402|Name=Size
|RECORD=41|OwnerIndex=80|IndexInSheet=13|OwnerPartId=-1|Location.X=1078|Location.Y=656|Color=8388608|FontID=7|IsHidden=T|Name=SUB
|RECORD=41|OwnerIndex=80|IndexInSheet=14|OwnerPartId=-1|Location.X=1078|Location.Y=656|Color=8388608|FontID=1|IsHidden=T|Text=CAP, CER, 0.1UF, 50V, 10%, X7R, AEC-Q200, 0402|Name=DESC
|RECORD=41|OwnerIndex=80|IndexInSheet=15|OwnerPartId=-1|Location.X=1078|Location.Y=656|Color=8388608|FontID=1|IsHidden=T|Text=Digi-Key|Name=Supplier 1|ReadOnlyState=3
|RECORD=41|OwnerIndex=80|IndexInSheet=16|OwnerPartId=-1|Location.X=1078|Location.Y=656|Color=8388608|FontID=1|IsHidden=T|Text=445-6899-1-ND|Name=Supplier Part Number 1|ReadOnlyState=3
|RECORD=41|OwnerIndex=80|IndexInSheet=17|OwnerPartId=-1|Location.X=1101|Location.Y=638|Color=8388608|FontID=7|Text=0.1UF|Name=VALUE
|RECORD=2|OwnerIndex=80|OwnerPartId=1|FormalType=1|Electrical=4|PinConglomerate=32|PinLength=10|Location.X=1100|Location.Y=650|Name=2|Designator=2|SwapIdPin=2|SwapIDPart=1|PinPropagationDelay=0.000000E+000
|RECORD=2|OwnerIndex=80|OwnerPartId=1|FormalType=1|Electrical=4|PinConglomerate=34|PinLength=10|Location.X=1090|Location.Y=650|Name=1|Designator=1|SwapIdPin=1|SwapIDPart=1|PinPropagationDelay=0.000000E+000
|RECORD=13|OwnerIndex=80|IsNotAccesible=T|IndexInSheet=20|OwnerPartId=1|Location.X=1097|Location.X_Frac=50000|Location.Y=650|Corner.X=1100|Corner.Y=650|LineWidth=1|Color=16711680
|RECORD=13|OwnerIndex=80|IsNotAccesible=T|IndexInSheet=21|OwnerPartId=1|Location.X=1090|Location.Y=650|Corner.X=1092|Corner.X_Frac=50000|Corner.Y=650|LineWidth=1|Color=16711680
|RECORD=13|OwnerIndex=80|IsNotAccesible=T|IndexInSheet=22|OwnerPartId=1|Location.X=1097|Location.X_Frac=50000|Location.Y=655|Corner.X=1097|Corner.X_Frac=50000|Corner.Y=645|LineWidth=1|Color=16711680
|RECORD=13|OwnerIndex=80|IsNotAccesible=T|IndexInSheet=23|OwnerPartId=1|Location.X=1092|Location.X_Frac=50000|Location.Y=655|Corner.X=1092|Corner.X_Frac=50000|Corner.Y=645|LineWidth=1|Color=16711680
|RECORD=41|OwnerIndex=80|IndexInSheet=24|OwnerPartId=-1|Location.X=1078|Location.Y=656|Color=8388608|FontID=1|IsHidden=T|Text=<VALENTIUM>|Name=VALENTIUM PART NUM
|RECORD=34|OwnerIndex=80|IndexInSheet=-1|OwnerPartId=-1|Location.X=1070|Location.Y=636|Color=8388608|FontID=1|Text=C53|Name=Designator|ReadOnlyState=1
|RECORD=41|OwnerIndex=80|IndexInSheet=-1|OwnerPartId=-1|Location.X=1078|Location.Y=656|Color=8388608|FontID=1|IsHidden=T|Text=CAP_0402_0.1UF_50V|Name=Comment|ReadOnlyState=1
|RECORD=44|OwnerIndex=80
|RECORD=45|OwnerIndex=110|IndexInSheet=-1|Description=Chip Capacitor, 0402, 2-Leads, Body 1.00x0.50mm, IPC Medium Density|UseComponentLibrary=T|ModelName=CAPC1005X06N|ModelType=PCBLIB|DatafileCount=1|ModelDatafileEntity0=CAPC1005X06N|ModelDatafileKind0=PCBLib|IsCurrent=T|DatalinksLocked=T|DatabaseDatalinksLocked=T|IntegratedModel=T|DatabaseModel=T
|RECORD=46|OwnerIndex=111
|RECORD=48|OwnerIndex=111
|RECORD=1|LibReference=CAP_0402_0.1UF_50V|ComponentDescription=CAP, CER, 0.1UF, 50V, 10%, X7R, AEC-Q200, 0402|PartCount=2|DisplayModeCount=1|IndexInSheet=35|OwnerPartId=-1|Location.X=1090|Location.Y=640|Orientation=1|CurrentPartId=1|LibraryPath=*|SourceLibraryName=Capacitors.IntLib|TargetFileName=*|AreaColor=11599871|Color=128|PartIDLocked=F|DesignItemId=CAP_0402_0.1UF_50V|AllPinCount=2
|RECORD=41|OwnerIndex=114|OwnerPartId=-1|Location.X=1038|Location.Y=666|Color=8388608|FontID=7|IsHidden=T|Text=CAP, CER|Name=CATEGORY
|RECORD=41|OwnerIndex=114|IndexInSheet=1|OwnerPartId=-1|Location.X=1038|Location.Y=666|Color=8388608|FontID=7|IsHidden=T|Text=TDK|Name=MFG NAME
|RECORD=41|OwnerIndex=114|IndexInSheet=2|OwnerPartId=-1|Location.X=1038|Location.Y=666|Color=8388608|FontID=7|IsHidden=T|Text=CGA2B3X7R1H104K050BB|Name=MFG PART NUM
|RECORD=41|OwnerIndex=114|IndexInSheet=3|OwnerPartId=-1|Location.X=1038|Location.Y=666|Color=8388608|FontID=7|IsHidden=T|Text=10/23/2013|Name=MODIFY DATE
|RECORD=41|OwnerIndex=114|IndexInSheet=4|OwnerPartId=-1|Location.X=1038|Location.Y=666|Color=8388608|FontID=7|IsHidden=T|Name=Date
|RECORD=41|OwnerIndex=114|IndexInSheet=5|OwnerPartId=-1|Location.X=1038|Location.Y=666|Color=8388608|FontID=7|IsHidden=T|Text=*|Name=SHEETPART
|RECORD=41|OwnerIndex=114|IndexInSheet=6|OwnerPartId=-1|Location.X=1038|Location.Y=666|Color=8388608|FontID=7|IsHidden=T|Text=10%|Name=P1
|RECORD=41|OwnerIndex=114|IndexInSheet=7|OwnerPartId=-1|Location.X=1038|Location.Y=666|Color=8388608|FontID=7|IsHidden=T|Text=125C|Name=MAXTEMP
|RECORD=41|OwnerIndex=114|IndexInSheet=8|OwnerPartId=-1|Location.X=1038|Location.Y=666|Color=8388608|FontID=7|IsHidden=T|Text=-55C|Name=MINTEMP
|RECORD=41|OwnerIndex=114|IndexInSheet=9|OwnerPartId=-1|Location.X=1038|Location.Y=666|Color=8388608|FontID=7|IsHidden=T|Text=AEC-Q200|Name=OTHER
|RECORD=41|OwnerIndex=114|IndexInSheet=10|OwnerPartId=-1|Location.X=1038|Location.Y=666|Color=8388608|FontID=7|IsHidden=T|Text=50V|Name=P2
|RECORD=41|OwnerIndex=114|IndexInSheet=11|OwnerPartId=-1|Location.X=1038|Location.Y=666|Color=8388608|FontID=7|IsHidden=T|Text=X7R|Name=P3
|RECORD=41|OwnerIndex=114|IndexInSheet=12|OwnerPartId=-1|Location.X=1038|Location.Y=666|Color=8388608|FontID=7|IsHidden=T|Text=0402|Name=Size
|RECORD=41|OwnerIndex=114|IndexInSheet=13|OwnerPartId=-1|Location.X=1038|Location.Y=666|Color=8388608|FontID=7|IsHidden=T|Name=SUB
|RECORD=41|OwnerIndex=114|IndexInSheet=14|OwnerPartId=-1|Location.X=1038|Location.Y=666|Color=8388608|FontID=1|IsHidden=T|Text=CAP, CER, 0.1UF, 50V, 10%, X7R, AEC-Q200, 0402|Name=DESC
|RECORD=41|OwnerIndex=114|IndexInSheet=15|OwnerPartId=-1|Location.X=1038|Location.Y=666|Color=8388608|FontID=1|IsHidden=T|Text=Digi-Key|Name=Supplier 1|ReadOnlyState=3
|RECORD=41|OwnerIndex=114|IndexInSheet=16|OwnerPartId=-1|Location.X=1038|Location.Y=666|Color=8388608|FontID=1|IsHidden=T|Text=445-6899-1-ND|Name=Supplier Part Number 1|ReadOnlyState=3
|RECORD=41|OwnerIndex=114|IndexInSheet=17|OwnerPartId=-1|Location.X=1060|Location.Y=660|Color=8388608|FontID=7|Text=0.1UF|Name=VALUE
|RECORD=2|OwnerIndex=114|OwnerPartId=1|FormalType=1|Electrical=4|PinConglomerate=32|PinLength=10|Location.X=1060|Location.Y=660|Name=2|Designator=2|SwapIdPin=2|SwapIDPart=1|PinPropagationDelay=0.000000E+000
|RECORD=2|OwnerIndex=114|OwnerPartId=1|FormalType=1|Electrical=4|PinConglomerate=34|PinLength=10|Location.X=1050|Location.Y=660|Name=1|Designator=1|SwapIdPin=1|SwapIDPart=1|PinPropagationDelay=0.000000E+000
|RECORD=13|OwnerIndex=114|IsNotAccesible=T|IndexInSheet=20|OwnerPartId=1|Location.X=1057|Location.X_Frac=50000|Location.Y=660|Corner.X=1060|Corner.Y=660|LineWidth=1|Color=16711680
|RECORD=13|OwnerIndex=114|IsNotAccesible=T|IndexInSheet=21|OwnerPartId=1|Location.X=1050|Location.Y=660|Corner.X=1052|Corner.X_Frac=50000|Corner.Y=660|LineWidth=1|Color=16711680
|RECORD=13|OwnerIndex=114|IsNotAccesible=T|IndexInSheet=22|OwnerPartId=1|Location.X=1057|Location.X_Frac=50000|Location.Y=665|Corner.X=1057|Corner.X_Frac=50000|Corner.Y=655|LineWidth=1|Color=16711680
|RECORD=13|OwnerIndex=114|IsNotAccesible=T|IndexInSheet=23|OwnerPartId=1|Location.X=1052|Location.X_Frac=50000|Location.Y=665|Corner.X=1052|Corner.X_Frac=50000|Corner.Y=655|LineWidth=1|Color=16711680
|RECORD=41|OwnerIndex=114|IndexInSheet=24|OwnerPartId=-1|Location.X=1038|Location.Y=666|Color=8388608|FontID=1|IsHidden=T|Text=<VALENTIUM>|Name=VALENTIUM PART NUM
|RECORD=34|OwnerIndex=114|IndexInSheet=-1|OwnerPartId=-1|Location.X=1030|Location.Y=660|Color=8388608|FontID=1|Text=C52|Name=Designator|ReadOnlyState=1
|RECORD=41|OwnerIndex=114|IndexInSheet=-1|OwnerPartId=-1|Location.X=1038|Location.Y=666|Color=8388608|FontID=1|IsHidden=T|Text=CAP_0402_0.1UF_50V|Name=Comment|ReadOnlyState=1
|RECORD=44|OwnerIndex=114
|RECORD=45|OwnerIndex=144|IndexInSheet=-1|Description=Chip Capacitor, 0402, 2-Leads, Body 1.00x0.50mm, IPC Medium Density|UseComponentLibrary=T|ModelName=CAPC1005X06N|ModelType=PCBLIB|DatafileCount=1|ModelDatafileEntity0=CAPC1005X06N|ModelDatafileKind0=PCBLib|IsCurrent=T|DatalinksLocked=T|DatabaseDatalinksLocked=T|IntegratedModel=T|DatabaseModel=T
|RECORD=46|OwnerIndex=145
|RECORD=48|OwnerIndex=145
|RECORD=1|LibReference=RES_0402_0|ComponentDescription=RES, 0. OHM, 1%, 1/16W, TF, AEC-Q200, 0402|PartCount=2|DisplayModeCount=1|IndexInSheet=36|OwnerPartId=-1|Location.X=670|Location.Y=640|CurrentPartId=1|LibraryPath=*|SourceLibraryName=Resistors.IntLib|TargetFileName=*|AreaColor=11599871|Color=128|PartIDLocked=F|DesignItemId=RES_0402_0|AllPinCount=2
|RECORD=41|OwnerIndex=148|OwnerPartId=-1|Location.X=670|Location.Y=640|Color=8388608|FontID=7|IsHidden=T|Text=7/25/2013|Name=ModifyDate
|RECORD=41|OwnerIndex=148|IndexInSheet=1|OwnerPartId=-1|Location.X=670|Location.Y=640|Color=8388608|FontID=7|IsHidden=T|Text=ERJ-2GE0R00X|Name=MFG PART NUM
|RECORD=41|OwnerIndex=148|IndexInSheet=2|OwnerPartId=-1|Location.X=670|Location.Y=640|Color=8388608|FontID=7|IsHidden=T|Text=PANASONIC|Name=MFG NAME
|RECORD=41|OwnerIndex=148|IndexInSheet=3|OwnerPartId=-1|Location.X=670|Location.Y=640|Color=8388608|FontID=7|IsHidden=T|Text=RES|Name=CATEGORY
|RECORD=41|OwnerIndex=148|IndexInSheet=4|OwnerPartId=-1|Location.X=668|Location.Y=650|Color=8388608|FontID=7|IsHidden=T|Text=7/26/2013|Name=Date
|RECORD=41|OwnerIndex=148|IndexInSheet=5|OwnerPartId=-1|Location.X=660|Location.X_Frac=55769|Location.Y=650|Color=8388608|FontID=7|IsHidden=T|Text=1%|Name=P1
|RECORD=41|OwnerIndex=148|IndexInSheet=6|OwnerPartId=-1|Location.X=660|Location.X_Frac=55769|Location.Y=650|Color=8388608|FontID=7|IsHidden=T|Text=TF|Name=P3
|RECORD=41|OwnerIndex=148|IndexInSheet=7|OwnerPartId=-1|Location.X=660|Location.X_Frac=55769|Location.Y=650|Color=8388608|FontID=7|IsHidden=T|Text=1/16W|Name=P2
|RECORD=41|OwnerIndex=148|IndexInSheet=8|OwnerPartId=-1|Location.X=660|Location.X_Frac=55769|Location.Y=650|Color=8388608|FontID=7|IsHidden=T|Text=155C|Name=MAXTEMP
|RECORD=41|OwnerIndex=148|IndexInSheet=9|OwnerPartId=-1|Location.X=660|Location.X_Frac=55769|Location.Y=650|Color=8388608|FontID=7|IsHidden=T|Text=-55C|Name=MINTEMP
|RECORD=41|OwnerIndex=148|IndexInSheet=10|OwnerPartId=-1|Location.X=660|Location.X_Frac=55769|Location.Y=650|Color=8388608|FontID=7|IsHidden=T|Text=100PPM, AEC-Q200|Name=OTHER
|RECORD=41|OwnerIndex=148|IndexInSheet=11|OwnerPartId=-1|Location.X=660|Location.X_Frac=55769|Location.Y=650|Color=8388608|FontID=7|IsHidden=T|Text=0402|Name=SIZE
|RECORD=41|OwnerIndex=148|IndexInSheet=12|OwnerPartId=-1|Location.X=660|Location.X_Frac=55769|Location.Y=650|Color=8388608|FontID=7|IsHidden=T|Text=GENERIC|Name=SUB
|RECORD=41|OwnerIndex=148|IndexInSheet=13|OwnerPartId=-1|Location.X=655|Location.X_Frac=98077|Location.Y=626|Color=8388608|FontID=1|IsHidden=T|Text=*|Name=SHEETPART
|RECORD=41|OwnerIndex=148|IndexInSheet=14|OwnerPartId=-1|Location.X=655|Location.X_Frac=98077|Location.Y=654|Color=8388608|FontID=1|IsHidden=T|Text=RES, 0 OHM, 1%, 1/16W, TF, AEC-Q200, 0402|Name=DESC
|RECORD=41|OwnerIndex=148|IndexInSheet=15|OwnerPartId=-1|Location.X=656|Location.X_Frac=60577|Location.Y=654|Color=8388608|FontID=1|IsHidden=T|Text=Digi-Key|Name=Supplier 1|ReadOnlyState=3
|RECORD=41|OwnerIndex=148|IndexInSheet=16|OwnerPartId=-1|Location.X=656|Location.X_Frac=60577|Location.Y=654|Color=8388608|FontID=1|IsHidden=T|Text=P0.0JCT-ND|Name=Supplier Part Number 1|ReadOnlyState=3
|RECORD=41|OwnerIndex=148|IndexInSheet=17|OwnerPartId=-1|Location.X=656|Location.X_Frac=61102|Location.Y=654|Color=8388608|FontID=1|IsHidden=T|Text=<VELENTIUM>|Name=VELENTIUM PART NUM
|RECORD=41|OwnerIndex=148|IndexInSheet=18|OwnerPartId=-1|Location.X=679|Location.Y=624|Color=8388608|FontID=7|Text=0 OHM|Name=VALUE
|RECORD=2|OwnerIndex=148|OwnerPartId=1|FormalType=1|Electrical=4|PinConglomerate=34|PinLength=10|Location.X=680|Location.Y=640|Name=1|Designator=1|PinPropagationDelay=0.000000E+000
|RECORD=2|OwnerIndex=148|OwnerPartId=1|FormalType=1|Electrical=4|PinConglomerate=32|PinLength=10|Location.X=710|Location.Y=640|Name=2|Designator=2|PinPropagationDelay=0.000000E+000
|RECORD=6|OwnerIndex=148|IsNotAccesible=T|IndexInSheet=21|OwnerPartId=1|LineWidth=1|Color=16711680|LocationCount=7|X1=710|Y1=640|X2=707|Y2=643|X3=701|Y3=637|X4=695|Y4=643|X5=689|Y5=637|X6=683|Y6=643|X7=680|Y7=640
|RECORD=34|OwnerIndex=148|IndexInSheet=-1|OwnerPartId=-1|Location.X=679|Location.Y=644|Color=8388608|FontID=1|Text=R24|Name=Designator|ReadOnlyState=1
|RECORD=41|OwnerIndex=148|IndexInSheet=-1|OwnerPartId=-1|Location.X=690|Location.Y=630|Color=8388608|FontID=1|IsHidden=T|Text=="MFG PART NUM"|Name=Comment
|RECORD=44|OwnerIndex=148
|RECORD=45|OwnerIndex=175|IndexInSheet=-1|Description=Chip Resistor, 0402, 2-Leads, Body 1.00x0.50mm, IPC Medium Density|UseComponentLibrary=T|ModelName=RESC1005X04N|ModelType=PCBLIB|DatafileCount=1|ModelDatafileEntity0=RESC1005X04N|ModelDatafileKind0=PCBLib|IsCurrent=T|DatalinksLocked=T|DatabaseDatalinksLocked=T|IntegratedModel=T|DatabaseModel=T
|RECORD=46|OwnerIndex=176
|RECORD=48|OwnerIndex=176
|RECORD=1|LibReference=RES_0402_0|ComponentDescription=RES, 0. OHM, 1%, 1/16W, TF, AEC-Q200, 0402|PartCount=2|DisplayModeCount=1|IndexInSheet=37|OwnerPartId=-1|Location.X=670|Location.Y=780|CurrentPartId=1|LibraryPath=*|SourceLibraryName=Resistors.IntLib|TargetFileName=*|AreaColor=11599871|Color=128|PartIDLocked=F|DesignItemId=RES_0402_0|AllPinCount=2
|RECORD=41|OwnerIndex=179|OwnerPartId=-1|Location.X=670|Location.Y=780|Color=8388608|FontID=7|IsHidden=T|Text=7/25/2013|Name=ModifyDate
|RECORD=41|OwnerIndex=179|IndexInSheet=1|OwnerPartId=-1|Location.X=670|Location.Y=780|Color=8388608|FontID=7|IsHidden=T|Text=ERJ-2GE0R00X|Name=MFG PART NUM
|RECORD=41|OwnerIndex=179|IndexInSheet=2|OwnerPartId=-1|Location.X=670|Location.Y=780|Color=8388608|FontID=7|IsHidden=T|Text=PANASONIC|Name=MFG NAME
|RECORD=41|OwnerIndex=179|IndexInSheet=3|OwnerPartId=-1|Location.X=670|Location.Y=780|Color=8388608|FontID=7|IsHidden=T|Text=RES|Name=CATEGORY
|RECORD=41|OwnerIndex=179|IndexInSheet=4|OwnerPartId=-1|Location.X=668|Location.Y=790|Color=8388608|FontID=7|IsHidden=T|Text=7/26/2013|Name=Date
|RECORD=41|OwnerIndex=179|IndexInSheet=5|OwnerPartId=-1|Location.X=660|Location.X_Frac=55769|Location.Y=790|Color=8388608|FontID=7|IsHidden=T|Text=1%|Name=P1
|RECORD=41|OwnerIndex=179|IndexInSheet=6|OwnerPartId=-1|Location.X=660|Location.X_Frac=55769|Location.Y=790|Color=8388608|FontID=7|IsHidden=T|Text=TF|Name=P3
|RECORD=41|OwnerIndex=179|IndexInSheet=7|OwnerPartId=-1|Location.X=660|Location.X_Frac=55769|Location.Y=790|Color=8388608|FontID=7|IsHidden=T|Text=1/16W|Name=P2
|RECORD=41|OwnerIndex=179|IndexInSheet=8|OwnerPartId=-1|Location.X=660|Location.X_Frac=55769|Location.Y=790|Color=8388608|FontID=7|IsHidden=T|Text=155C|Name=MAXTEMP
|RECORD=41|OwnerIndex=179|IndexInSheet=9|OwnerPartId=-1|Location.X=660|Location.X_Frac=55769|Location.Y=790|Color=8388608|FontID=7|IsHidden=T|Text=-55C|Name=MINTEMP
|RECORD=41|OwnerIndex=179|IndexInSheet=10|OwnerPartId=-1|Location.X=660|Location.X_Frac=55769|Location.Y=790|Color=8388608|FontID=7|IsHidden=T|Text=100PPM, AEC-Q200|Name=OTHER
|RECORD=41|OwnerIndex=179|IndexInSheet=11|OwnerPartId=-1|Location.X=660|Location.X_Frac=55769|Location.Y=790|Color=8388608|FontID=7|IsHidden=T|Text=0402|Name=SIZE
|RECORD=41|OwnerIndex=179|IndexInSheet=12|OwnerPartId=-1|Location.X=660|Location.X_Frac=55769|Location.Y=790|Color=8388608|FontID=7|IsHidden=T|Text=GENERIC|Name=SUB
|RECORD=41|OwnerIndex=179|IndexInSheet=13|OwnerPartId=-1|Location.X=655|Location.X_Frac=98077|Location.Y=766|Color=8388608|FontID=1|IsHidden=T|Text=*|Name=SHEETPART
|RECORD=41|OwnerIndex=179|IndexInSheet=14|OwnerPartId=-1|Location.X=655|Location.X_Frac=98077|Location.Y=794|Color=8388608|FontID=1|IsHidden=T|Text=RES, 0 OHM, 1%, 1/16W, TF, AEC-Q200, 0402|Name=DESC
|RECORD=41|OwnerIndex=179|IndexInSheet=15|OwnerPartId=-1|Location.X=656|Location.X_Frac=60577|Location.Y=794|Color=8388608|FontID=1|IsHidden=T|Text=Digi-Key|Name=Supplier 1|ReadOnlyState=3
|RECORD=41|OwnerIndex=179|IndexInSheet=16|OwnerPartId=-1|Location.X=656|Location.X_Frac=60577|Location.Y=794|Color=8388608|FontID=1|IsHidden=T|Text=P0.0JCT-ND|Name=Supplier Part Number 1|ReadOnlyState=3
|RECORD=41|OwnerIndex=179|IndexInSheet=17|OwnerPartId=-1|Location.X=656|Location.X_Frac=61102|Location.Y=794|Color=8388608|FontID=1|IsHidden=T|Text=<VELENTIUM>|Name=VELENTIUM PART NUM
|RECORD=41|OwnerIndex=179|IndexInSheet=18|OwnerPartId=-1|Location.X=679|Location.Y=764|Color=8388608|FontID=7|Text=0 OHM|Name=VALUE
|RECORD=2|OwnerIndex=179|OwnerPartId=1|FormalType=1|Electrical=4|PinConglomerate=34|PinLength=10|Location.X=680|Location.Y=780|Name=1|Designator=1|PinPropagationDelay=0.000000E+000
|RECORD=2|OwnerIndex=179|OwnerPartId=1|FormalType=1|Electrical=4|PinConglomerate=32|PinLength=10|Location.X=710|Location.Y=780|Name=2|Designator=2|PinPropagationDelay=0.000000E+000
|RECORD=6|OwnerIndex=179|IsNotAccesible=T|IndexInSheet=21|OwnerPartId=1|LineWidth=1|Color=16711680|LocationCount=7|X1=710|Y1=780|X2=707|Y2=783|X3=701|Y3=777|X4=695|Y4=783|X5=689|Y5=777|X6=683|Y6=783|X7=680|Y7=780
|RECORD=34|OwnerIndex=179|IndexInSheet=-1|OwnerPartId=-1|Location.X=679|Location.Y=784|Color=8388608|FontID=1|Text=R23|Name=Designator|ReadOnlyState=1
|RECORD=41|OwnerIndex=179|IndexInSheet=-1|OwnerPartId=-1|Location.X=690|Location.Y=770|Color=8388608|FontID=1|IsHidden=T|Text=="MFG PART NUM"|Name=Comment
|RECORD=44|OwnerIndex=179
|RECORD=45|OwnerIndex=206|IndexInSheet=-1|Description=Chip Resistor, 0402, 2-Leads, Body 1.00x0.50mm, IPC Medium Density|UseComponentLibrary=T|ModelName=RESC1005X04N|ModelType=PCBLIB|DatafileCount=1|ModelDatafileEntity0=RESC1005X04N|ModelDatafileKind0=PCBLib|IsCurrent=T|DatalinksLocked=T|DatabaseDatalinksLocked=T|IntegratedModel=T|DatabaseModel=T
|RECORD=46|OwnerIndex=207
|RECORD=48|OwnerIndex=207
|RECORD=1|LibReference=CAP_0402_0.1UF_50V|ComponentDescription=CAP, CER, 0.1UF, 50V, 10%, X7R, AEC-Q200, 0402|PartCount=2|DisplayModeCount=1|IndexInSheet=38|OwnerPartId=-1|Location.X=1130|Location.Y=670|Orientation=1|CurrentPartId=1|LibraryPath=*|SourceLibraryName=Capacitors.IntLib|TargetFileName=*|AreaColor=11599871|Color=128|PartIDLocked=F|DesignItemId=CAP_0402_0.1UF_50V|AllPinCount=2
|RECORD=41|OwnerIndex=210|OwnerPartId=-1|Location.X=1078|Location.Y=696|Color=8388608|FontID=7|IsHidden=T|Text=CAP, CER|Name=CATEGORY
|RECORD=41|OwnerIndex=210|IndexInSheet=1|OwnerPartId=-1|Location.X=1078|Location.Y=696|Color=8388608|FontID=7|IsHidden=T|Text=TDK|Name=MFG NAME
|RECORD=41|OwnerIndex=210|IndexInSheet=2|OwnerPartId=-1|Location.X=1078|Location.Y=696|Color=8388608|FontID=7|IsHidden=T|Text=CGA2B3X7R1H104K050BB|Name=MFG PART NUM
|RECORD=41|OwnerIndex=210|IndexInSheet=3|OwnerPartId=-1|Location.X=1078|Location.Y=696|Color=8388608|FontID=7|IsHidden=T|Text=10/23/2013|Name=MODIFY DATE
|RECORD=41|OwnerIndex=210|IndexInSheet=4|OwnerPartId=-1|Location.X=1078|Location.Y=696|Color=8388608|FontID=7|IsHidden=T|Name=Date
|RECORD=41|OwnerIndex=210|IndexInSheet=5|OwnerPartId=-1|Location.X=1078|Location.Y=696|Color=8388608|FontID=7|IsHidden=T|Text=*|Name=SHEETPART
|RECORD=41|OwnerIndex=210|IndexInSheet=6|OwnerPartId=-1|Location.X=1078|Location.Y=696|Color=8388608|FontID=7|IsHidden=T|Text=10%|Name=P1
|RECORD=41|OwnerIndex=210|IndexInSheet=7|OwnerPartId=-1|Location.X=1078|Location.Y=696|Color=8388608|FontID=7|IsHidden=T|Text=125C|Name=MAXTEMP
|RECORD=41|OwnerIndex=210|IndexInSheet=8|OwnerPartId=-1|Location.X=1078|Location.Y=696|Color=8388608|FontID=7|IsHidden=T|Text=-55C|Name=MINTEMP
|RECORD=41|OwnerIndex=210|IndexInSheet=9|OwnerPartId=-1|Location.X=1078|Location.Y=696|Color=8388608|FontID=7|IsHidden=T|Text=AEC-Q200|Name=OTHER
|RECORD=41|OwnerIndex=210|IndexInSheet=10|OwnerPartId=-1|Location.X=1078|Location.Y=696|Color=8388608|FontID=7|IsHidden=T|Text=50V|Name=P2
|RECORD=41|OwnerIndex=210|IndexInSheet=11|OwnerPartId=-1|Location.X=1078|Location.Y=696|Color=8388608|FontID=7|IsHidden=T|Text=X7R|Name=P3
|RECORD=41|OwnerIndex=210|IndexInSheet=12|OwnerPartId=-1|Location.X=1078|Location.Y=696|Color=8388608|FontID=7|IsHidden=T|Text=0402|Name=Size
|RECORD=41|OwnerIndex=210|IndexInSheet=13|OwnerPartId=-1|Location.X=1078|Location.Y=696|Color=8388608|FontID=7|IsHidden=T|Name=SUB
|RECORD=41|OwnerIndex=210|IndexInSheet=14|OwnerPartId=-1|Location.X=1078|Location.Y=696|Color=8388608|FontID=1|IsHidden=T|Text=CAP, CER, 0.1UF, 50V, 10%, X7R, AEC-Q200, 0402|Name=DESC
|RECORD=41|OwnerIndex=210|IndexInSheet=15|OwnerPartId=-1|Location.X=1078|Location.Y=696|Color=8388608|FontID=1|IsHidden=T|Text=Digi-Key|Name=Supplier 1|ReadOnlyState=3
|RECORD=41|OwnerIndex=210|IndexInSheet=16|OwnerPartId=-1|Location.X=1078|Location.Y=696|Color=8388608|FontID=1|IsHidden=T|Text=445-6899-1-ND|Name=Supplier Part Number 1|ReadOnlyState=3
|RECORD=41|OwnerIndex=210|IndexInSheet=17|OwnerPartId=-1|Location.X=1101|Location.Y=678|Color=8388608|FontID=7|Text=0.1UF|Name=VALUE
|RECORD=2|OwnerIndex=210|OwnerPartId=1|FormalType=1|Electrical=4|PinConglomerate=32|PinLength=10|Location.X=1100|Location.Y=690|Name=2|Designator=2|SwapIdPin=2|SwapIDPart=1|PinPropagationDelay=0.000000E+000
|RECORD=2|OwnerIndex=210|OwnerPartId=1|FormalType=1|Electrical=4|PinConglomerate=34|PinLength=10|Location.X=1090|Location.Y=690|Name=1|Designator=1|SwapIdPin=1|SwapIDPart=1|PinPropagationDelay=0.000000E+000
|RECORD=13|OwnerIndex=210|IsNotAccesible=T|IndexInSheet=20|OwnerPartId=1|Location.X=1097|Location.X_Frac=50000|Location.Y=690|Corner.X=1100|Corner.Y=690|LineWidth=1|Color=16711680
|RECORD=13|OwnerIndex=210|IsNotAccesible=T|IndexInSheet=21|OwnerPartId=1|Location.X=1090|Location.Y=690|Corner.X=1092|Corner.X_Frac=50000|Corner.Y=690|LineWidth=1|Color=16711680
|RECORD=13|OwnerIndex=210|IsNotAccesible=T|IndexInSheet=22|OwnerPartId=1|Location.X=1097|Location.X_Frac=50000|Location.Y=695|Corner.X=1097|Corner.X_Frac=50000|Corner.Y=685|LineWidth=1|Color=16711680
|RECORD=13|OwnerIndex=210|IsNotAccesible=T|IndexInSheet=23|OwnerPartId=1|Location.X=1092|Location.X_Frac=50000|Location.Y=695|Corner.X=1092|Corner.X_Frac=50000|Corner.Y=685|LineWidth=1|Color=16711680
|RECORD=41|OwnerIndex=210|IndexInSheet=24|OwnerPartId=-1|Location.X=1078|Location.Y=696|Color=8388608|FontID=1|IsHidden=T|Text=<VALENTIUM>|Name=VALENTIUM PART NUM
|RECORD=34|OwnerIndex=210|IndexInSheet=-1|OwnerPartId=-1|Location.X=1070|Location.Y=676|Color=8388608|FontID=1|Text=C51|Name=Designator|ReadOnlyState=1
|RECORD=41|OwnerIndex=210|IndexInSheet=-1|OwnerPartId=-1|Location.X=1078|Location.Y=696|Color=8388608|FontID=1|IsHidden=T|Text=CAP_0402_0.1UF_50V|Name=Comment|ReadOnlyState=1
|RECORD=44|OwnerIndex=210
|RECORD=45|OwnerIndex=240|IndexInSheet=-1|Description=Chip Capacitor, 0402, 2-Leads, Body 1.00x0.50mm, IPC Medium Density|UseComponentLibrary=T|ModelName=CAPC1005X06N|ModelType=PCBLIB|DatafileCount=1|ModelDatafileEntity0=CAPC1005X06N|ModelDatafileKind0=PCBLib|IsCurrent=T|DatalinksLocked=T|DatabaseDatalinksLocked=T|IntegratedModel=T|DatabaseModel=T
|RECORD=46|OwnerIndex=241
|RECORD=48|OwnerIndex=241
|RECORD=1|LibReference=CAP_0402_0.1UF_50V|ComponentDescription=CAP, CER, 0.1UF, 50V, 10%, X7R, AEC-Q200, 0402|PartCount=2|DisplayModeCount=1|IndexInSheet=39|OwnerPartId=-1|Location.X=1130|Location.Y=710|Orientation=1|CurrentPartId=1|LibraryPath=*|SourceLibraryName=Capacitors.IntLib|TargetFileName=*|AreaColor=11599871|Color=128|PartIDLocked=F|DesignItemId=CAP_0402_0.1UF_50V|AllPinCount=2
|RECORD=41|OwnerIndex=244|OwnerPartId=-1|Location.X=1078|Location.Y=736|Color=8388608|FontID=7|IsHidden=T|Text=CAP, CER|Name=CATEGORY
|RECORD=41|OwnerIndex=244|IndexInSheet=1|OwnerPartId=-1|Location.X=1078|Location.Y=736|Color=8388608|FontID=7|IsHidden=T|Text=TDK|Name=MFG NAME
|RECORD=41|OwnerIndex=244|IndexInSheet=2|OwnerPartId=-1|Location.X=1078|Location.Y=736|Color=8388608|FontID=7|IsHidden=T|Text=CGA2B3X7R1H104K050BB|Name=MFG PART NUM
|RECORD=41|OwnerIndex=244|IndexInSheet=3|OwnerPartId=-1|Location.X=1078|Location.Y=736|Color=8388608|FontID=7|IsHidden=T|Text=10/23/2013|Name=MODIFY DATE
|RECORD=41|OwnerIndex=244|IndexInSheet=4|OwnerPartId=-1|Location.X=1078|Location.Y=736|Color=8388608|FontID=7|IsHidden=T|Name=Date
|RECORD=41|OwnerIndex=244|IndexInSheet=5|OwnerPartId=-1|Location.X=1078|Location.Y=736|Color=8388608|FontID=7|IsHidden=T|Text=*|Name=SHEETPART
|RECORD=41|OwnerIndex=244|IndexInSheet=6|OwnerPartId=-1|Location.X=1078|Location.Y=736|Color=8388608|FontID=7|IsHidden=T|Text=10%|Name=P1
|RECORD=41|OwnerIndex=244|IndexInSheet=7|OwnerPartId=-1|Location.X=1078|Location.Y=736|Color=8388608|FontID=7|IsHidden=T|Text=125C|Name=MAXTEMP
|RECORD=41|OwnerIndex=244|IndexInSheet=8|OwnerPartId=-1|Location.X=1078|Location.Y=736|Color=8388608|FontID=7|IsHidden=T|Text=-55C|Name=MINTEMP
|RECORD=41|OwnerIndex=244|IndexInSheet=9|OwnerPartId=-1|Location.X=1078|Location.Y=736|Color=8388608|FontID=7|IsHidden=T|Text=AEC-Q200|Name=OTHER
|RECORD=41|OwnerIndex=244|IndexInSheet=10|OwnerPartId=-1|Location.X=1078|Location.Y=736|Color=8388608|FontID=7|IsHidden=T|Text=50V|Name=P2
|RECORD=41|OwnerIndex=244|IndexInSheet=11|OwnerPartId=-1|Location.X=1078|Location.Y=736|Color=8388608|FontID=7|IsHidden=T|Text=X7R|Name=P3
|RECORD=41|OwnerIndex=244|IndexInSheet=12|OwnerPartId=-1|Location.X=1078|Location.Y=736|Color=8388608|FontID=7|IsHidden=T|Text=0402|Name=Size
|RECORD=41|OwnerIndex=244|IndexInSheet=13|OwnerPartId=-1|Location.X=1078|Location.Y=736|Color=8388608|FontID=7|IsHidden=T|Name=SUB
|RECORD=41|OwnerIndex=244|IndexInSheet=14|OwnerPartId=-1|Location.X=1078|Location.Y=736|Color=8388608|FontID=1|IsHidden=T|Text=CAP, CER, 0.1UF, 50V, 10%, X7R, AEC-Q200, 0402|Name=DESC
|RECORD=41|OwnerIndex=244|IndexInSheet=15|OwnerPartId=-1|Location.X=1078|Location.Y=736|Color=8388608|FontID=1|IsHidden=T|Text=Digi-Key|Name=Supplier 1|ReadOnlyState=3
|RECORD=41|OwnerIndex=244|IndexInSheet=16|OwnerPartId=-1|Location.X=1078|Location.Y=736|Color=8388608|FontID=1|IsHidden=T|Text=445-6899-1-ND|Name=Supplier Part Number 1|ReadOnlyState=3
|RECORD=41|OwnerIndex=244|IndexInSheet=17|OwnerPartId=-1|Location.X=1101|Location.Y=718|Color=8388608|FontID=7|Text=0.1UF|Name=VALUE
|RECORD=2|OwnerIndex=244|OwnerPartId=1|FormalType=1|Electrical=4|PinConglomerate=32|PinLength=10|Location.X=1100|Location.Y=730|Name=2|Designator=2|SwapIdPin=2|SwapIDPart=1|PinPropagationDelay=0.000000E+000
|RECORD=2|OwnerIndex=244|OwnerPartId=1|FormalType=1|Electrical=4|PinConglomerate=34|PinLength=10|Location.X=1090|Location.Y=730|Name=1|Designator=1|SwapIdPin=1|SwapIDPart=1|PinPropagationDelay=0.000000E+000
|RECORD=13|OwnerIndex=244|IsNotAccesible=T|IndexInSheet=20|OwnerPartId=1|Location.X=1097|Location.X_Frac=50000|Location.Y=730|Corner.X=1100|Corner.Y=730|LineWidth=1|Color=16711680
|RECORD=13|OwnerIndex=244|IsNotAccesible=T|IndexInSheet=21|OwnerPartId=1|Location.X=1090|Location.Y=730|Corner.X=1092|Corner.X_Frac=50000|Corner.Y=730|LineWidth=1|Color=16711680
|RECORD=13|OwnerIndex=244|IsNotAccesible=T|IndexInSheet=22|OwnerPartId=1|Location.X=1097|Location.X_Frac=50000|Location.Y=735|Corner.X=1097|Corner.X_Frac=50000|Corner.Y=725|LineWidth=1|Color=16711680
|RECORD=13|OwnerIndex=244|IsNotAccesible=T|IndexInSheet=23|OwnerPartId=1|Location.X=1092|Location.X_Frac=50000|Location.Y=735|Corner.X=1092|Corner.X_Frac=50000|Corner.Y=725|LineWidth=1|Color=16711680
|RECORD=41|OwnerIndex=244|IndexInSheet=24|OwnerPartId=-1|Location.X=1078|Location.Y=736|Color=8388608|FontID=1|IsHidden=T|Text=<VALENTIUM>|Name=VALENTIUM PART NUM
|RECORD=34|OwnerIndex=244|IndexInSheet=-1|OwnerPartId=-1|Location.X=1070|Location.Y=716|Color=8388608|FontID=1|Text=C49|Name=Designator|ReadOnlyState=1
|RECORD=41|OwnerIndex=244|IndexInSheet=-1|OwnerPartId=-1|Location.X=1078|Location.Y=736|Color=8388608|FontID=1|IsHidden=T|Text=CAP_0402_0.1UF_50V|Name=Comment|ReadOnlyState=1
|RECORD=44|OwnerIndex=244
|RECORD=45|OwnerIndex=274|IndexInSheet=-1|Description=Chip Capacitor, 0402, 2-Leads, Body 1.00x0.50mm, IPC Medium Density|UseComponentLibrary=T|ModelName=CAPC1005X06N|ModelType=PCBLIB|DatafileCount=1|ModelDatafileEntity0=CAPC1005X06N|ModelDatafileKind0=PCBLib|IsCurrent=T|DatalinksLocked=T|DatabaseDatalinksLocked=T|IntegratedModel=T|DatabaseModel=T
|RECORD=46|OwnerIndex=275
|RECORD=48|OwnerIndex=275
|RECORD=1|LibReference=CAP_0402_0.1UF_50V|ComponentDescription=CAP, CER, 0.1UF, 50V, 10%, X7R, AEC-Q200, 0402|PartCount=2|DisplayModeCount=1|IndexInSheet=40|OwnerPartId=-1|Location.X=1130|Location.Y=760|Orientation=1|CurrentPartId=1|LibraryPath=*|SourceLibraryName=Capacitors.IntLib|TargetFileName=*|AreaColor=11599871|Color=128|PartIDLocked=F|DesignItemId=CAP_0402_0.1UF_50V|AllPinCount=2
|RECORD=41|OwnerIndex=278|OwnerPartId=-1|Location.X=1078|Location.Y=786|Color=8388608|FontID=7|IsHidden=T|Text=CAP, CER|Name=CATEGORY
|RECORD=41|OwnerIndex=278|IndexInSheet=1|OwnerPartId=-1|Location.X=1078|Location.Y=786|Color=8388608|FontID=7|IsHidden=T|Text=TDK|Name=MFG NAME
|RECORD=41|OwnerIndex=278|IndexInSheet=2|OwnerPartId=-1|Location.X=1078|Location.Y=786|Color=8388608|FontID=7|IsHidden=T|Text=CGA2B3X7R1H104K050BB|Name=MFG PART NUM
|RECORD=41|OwnerIndex=278|IndexInSheet=3|OwnerPartId=-1|Location.X=1078|Location.Y=786|Color=8388608|FontID=7|IsHidden=T|Text=10/23/2013|Name=MODIFY DATE
|RECORD=41|OwnerIndex=278|IndexInSheet=4|OwnerPartId=-1|Location.X=1078|Location.Y=786|Color=8388608|FontID=7|IsHidden=T|Name=Date
|RECORD=41|OwnerIndex=278|IndexInSheet=5|OwnerPartId=-1|Location.X=1078|Location.Y=786|Color=8388608|FontID=7|IsHidden=T|Text=*|Name=SHEETPART
|RECORD=41|OwnerIndex=278|IndexInSheet=6|OwnerPartId=-1|Location.X=1078|Location.Y=786|Color=8388608|FontID=7|IsHidden=T|Text=10%|Name=P1
|RECORD=41|OwnerIndex=278|IndexInSheet=7|OwnerPartId=-1|Location.X=1078|Location.Y=786|Color=8388608|FontID=7|IsHidden=T|Text=125C|Name=MAXTEMP
|RECORD=41|OwnerIndex=278|IndexInSheet=8|OwnerPartId=-1|Location.X=1078|Location.Y=786|Color=8388608|FontID=7|IsHidden=T|Text=-55C|Name=MINTEMP
|RECORD=41|OwnerIndex=278|IndexInSheet=9|OwnerPartId=-1|Location.X=1078|Location.Y=786|Color=8388608|FontID=7|IsHidden=T|Text=AEC-Q200|Name=OTHER
|RECORD=41|OwnerIndex=278|IndexInSheet=10|OwnerPartId=-1|Location.X=1078|Location.Y=786|Color=8388608|FontID=7|IsHidden=T|Text=50V|Name=P2
|RECORD=41|OwnerIndex=278|IndexInSheet=11|OwnerPartId=-1|Location.X=1078|Location.Y=786|Color=8388608|FontID=7|IsHidden=T|Text=X7R|Name=P3
|RECORD=41|OwnerIndex=278|IndexInSheet=12|OwnerPartId=-1|Location.X=1078|Location.Y=786|Color=8388608|FontID=7|IsHidden=T|Text=0402|Name=Size
|RECORD=41|OwnerIndex=278|IndexInSheet=13|OwnerPartId=-1|Location.X=1078|Location.Y=786|Color=8388608|FontID=7|IsHidden=T|Name=SUB
|RECORD=41|OwnerIndex=278|IndexInSheet=14|OwnerPartId=-1|Location.X=1078|Location.Y=786|Color=8388608|FontID=1|IsHidden=T|Text=CAP, CER, 0.1UF, 50V, 10%, X7R, AEC-Q200, 0402|Name=DESC
|RECORD=41|OwnerIndex=278|IndexInSheet=15|OwnerPartId=-1|Location.X=1078|Location.Y=786|Color=8388608|FontID=1|IsHidden=T|Text=Digi-Key|Name=Supplier 1|ReadOnlyState=3
|RECORD=41|OwnerIndex=278|IndexInSheet=16|OwnerPartId=-1|Location.X=1078|Location.Y=786|Color=8388608|FontID=1|IsHidden=T|Text=445-6899-1-ND|Name=Supplier Part Number 1|ReadOnlyState=3
|RECORD=41|OwnerIndex=278|IndexInSheet=17|OwnerPartId=-1|Location.X=1101|Location.Y=768|Color=8388608|FontID=7|Text=0.1UF|Name=VALUE
|RECORD=2|OwnerIndex=278|OwnerPartId=1|FormalType=1|Electrical=4|PinConglomerate=32|PinLength=10|Location.X=1100|Location.Y=780|Name=2|Designator=2|SwapIdPin=2|SwapIDPart=1|PinPropagationDelay=0.000000E+000
|RECORD=2|OwnerIndex=278|OwnerPartId=1|FormalType=1|Electrical=4|PinConglomerate=34|PinLength=10|Location.X=1090|Location.Y=780|Name=1|Designator=1|SwapIdPin=1|SwapIDPart=1|PinPropagationDelay=0.000000E+000
|RECORD=13|OwnerIndex=278|IsNotAccesible=T|IndexInSheet=20|OwnerPartId=1|Location.X=1097|Location.X_Frac=50000|Location.Y=780|Corner.X=1100|Corner.Y=780|LineWidth=1|Color=16711680
|RECORD=13|OwnerIndex=278|IsNotAccesible=T|IndexInSheet=21|OwnerPartId=1|Location.X=1090|Location.Y=780|Corner.X=1092|Corner.X_Frac=50000|Corner.Y=780|LineWidth=1|Color=16711680
|RECORD=13|OwnerIndex=278|IsNotAccesible=T|IndexInSheet=22|OwnerPartId=1|Location.X=1097|Location.X_Frac=50000|Location.Y=785|Corner.X=1097|Corner.X_Frac=50000|Corner.Y=775|LineWidth=1|Color=16711680
|RECORD=13|OwnerIndex=278|IsNotAccesible=T|IndexInSheet=23|OwnerPartId=1|Location.X=1092|Location.X_Frac=50000|Location.Y=785|Corner.X=1092|Corner.X_Frac=50000|Corner.Y=775|LineWidth=1|Color=16711680
|RECORD=41|OwnerIndex=278|IndexInSheet=24|OwnerPartId=-1|Location.X=1078|Location.Y=786|Color=8388608|FontID=1|IsHidden=T|Text=<VALENTIUM>|Name=VALENTIUM PART NUM
|RECORD=34|OwnerIndex=278|IndexInSheet=-1|OwnerPartId=-1|Location.X=1070|Location.Y=766|Color=8388608|FontID=1|Text=C47|Name=Designator|ReadOnlyState=1
|RECORD=41|OwnerIndex=278|IndexInSheet=-1|OwnerPartId=-1|Location.X=1078|Location.Y=786|Color=8388608|FontID=1|IsHidden=T|Text=CAP_0402_0.1UF_50V|Name=Comment|ReadOnlyState=1
|RECORD=44|OwnerIndex=278
|RECORD=45|OwnerIndex=308|IndexInSheet=-1|Description=Chip Capacitor, 0402, 2-Leads, Body 1.00x0.50mm, IPC Medium Density|UseComponentLibrary=T|ModelName=CAPC1005X06N|ModelType=PCBLIB|DatafileCount=1|ModelDatafileEntity0=CAPC1005X06N|ModelDatafileKind0=PCBLib|IsCurrent=T|DatalinksLocked=T|DatabaseDatalinksLocked=T|IntegratedModel=T|DatabaseModel=T
|RECORD=46|OwnerIndex=309
|RECORD=48|OwnerIndex=309
|RECORD=1|LibReference=CAP_0402_0.1UF_50V|ComponentDescription=CAP, CER, 0.1UF, 50V, 10%, X7R, AEC-Q200, 0402|PartCount=2|DisplayModeCount=1|IndexInSheet=41|OwnerPartId=-1|Location.X=1130|Location.Y=790|Orientation=1|CurrentPartId=1|LibraryPath=*|SourceLibraryName=Capacitors.IntLib|TargetFileName=*|AreaColor=11599871|Color=128|PartIDLocked=F|DesignItemId=CAP_0402_0.1UF_50V|AllPinCount=2
|RECORD=41|OwnerIndex=312|OwnerPartId=-1|Location.X=1078|Location.Y=816|Color=8388608|FontID=7|IsHidden=T|Text=CAP, CER|Name=CATEGORY
|RECORD=41|OwnerIndex=312|IndexInSheet=1|OwnerPartId=-1|Location.X=1078|Location.Y=816|Color=8388608|FontID=7|IsHidden=T|Text=TDK|Name=MFG NAME
|RECORD=41|OwnerIndex=312|IndexInSheet=2|OwnerPartId=-1|Location.X=1078|Location.Y=816|Color=8388608|FontID=7|IsHidden=T|Text=CGA2B3X7R1H104K050BB|Name=MFG PART NUM
|RECORD=41|OwnerIndex=312|IndexInSheet=3|OwnerPartId=-1|Location.X=1078|Location.Y=816|Color=8388608|FontID=7|IsHidden=T|Text=10/23/2013|Name=MODIFY DATE
|RECORD=41|OwnerIndex=312|IndexInSheet=4|OwnerPartId=-1|Location.X=1078|Location.Y=816|Color=8388608|FontID=7|IsHidden=T|Name=Date
|RECORD=41|OwnerIndex=312|IndexInSheet=5|OwnerPartId=-1|Location.X=1078|Location.Y=816|Color=8388608|FontID=7|IsHidden=T|Text=*|Name=SHEETPART
|RECORD=41|OwnerIndex=312|IndexInSheet=6|OwnerPartId=-1|Location.X=1078|Location.Y=816|Color=8388608|FontID=7|IsHidden=T|Text=10%|Name=P1
|RECORD=41|OwnerIndex=312|IndexInSheet=7|OwnerPartId=-1|Location.X=1078|Location.Y=816|Color=8388608|FontID=7|IsHidden=T|Text=125C|Name=MAXTEMP
|RECORD=41|OwnerIndex=312|IndexInSheet=8|OwnerPartId=-1|Location.X=1078|Location.Y=816|Color=8388608|FontID=7|IsHidden=T|Text=-55C|Name=MINTEMP
|RECORD=41|OwnerIndex=312|IndexInSheet=9|OwnerPartId=-1|Location.X=1078|Location.Y=816|Color=8388608|FontID=7|IsHidden=T|Text=AEC-Q200|Name=OTHER
|RECORD=41|OwnerIndex=312|IndexInSheet=10|OwnerPartId=-1|Location.X=1078|Location.Y=816|Color=8388608|FontID=7|IsHidden=T|Text=50V|Name=P2
|RECORD=41|OwnerIndex=312|IndexInSheet=11|OwnerPartId=-1|Location.X=1078|Location.Y=816|Color=8388608|FontID=7|IsHidden=T|Text=X7R|Name=P3
|RECORD=41|OwnerIndex=312|IndexInSheet=12|OwnerPartId=-1|Location.X=1078|Location.Y=816|Color=8388608|FontID=7|IsHidden=T|Text=0402|Name=Size
|RECORD=41|OwnerIndex=312|IndexInSheet=13|OwnerPartId=-1|Location.X=1078|Location.Y=816|Color=8388608|FontID=7|IsHidden=T|Name=SUB
|RECORD=41|OwnerIndex=312|IndexInSheet=14|OwnerPartId=-1|Location.X=1078|Location.Y=816|Color=8388608|FontID=1|IsHidden=T|Text=CAP, CER, 0.1UF, 50V, 10%, X7R, AEC-Q200, 0402|Name=DESC
|RECORD=41|OwnerIndex=312|IndexInSheet=15|OwnerPartId=-1|Location.X=1078|Location.Y=816|Color=8388608|FontID=1|IsHidden=T|Text=Digi-Key|Name=Supplier 1|ReadOnlyState=3
|RECORD=41|OwnerIndex=312|IndexInSheet=16|OwnerPartId=-1|Location.X=1078|Location.Y=816|Color=8388608|FontID=1|IsHidden=T|Text=445-6899-1-ND|Name=Supplier Part Number 1|ReadOnlyState=3
|RECORD=41|OwnerIndex=312|IndexInSheet=17|OwnerPartId=-1|Location.X=1101|Location.Y=798|Color=8388608|FontID=7|Text=0.1UF|Name=VALUE
|RECORD=2|OwnerIndex=312|OwnerPartId=1|FormalType=1|Electrical=4|PinConglomerate=32|PinLength=10|Location.X=1100|Location.Y=810|Name=2|Designator=2|SwapIdPin=2|SwapIDPart=1|PinPropagationDelay=0.000000E+000
|RECORD=2|OwnerIndex=312|OwnerPartId=1|FormalType=1|Electrical=4|PinConglomerate=34|PinLength=10|Location.X=1090|Location.Y=810|Name=1|Designator=1|SwapIdPin=1|SwapIDPart=1|PinPropagationDelay=0.000000E+000
|RECORD=13|OwnerIndex=312|IsNotAccesible=T|IndexInSheet=20|OwnerPartId=1|Location.X=1097|Location.X_Frac=50000|Location.Y=810|Corner.X=1100|Corner.Y=810|LineWidth=1|Color=16711680
|RECORD=13|OwnerIndex=312|IsNotAccesible=T|IndexInSheet=21|OwnerPartId=1|Location.X=1090|Location.Y=810|Corner.X=1092|Corner.X_Frac=50000|Corner.Y=810|LineWidth=1|Color=16711680
|RECORD=13|OwnerIndex=312|IsNotAccesible=T|IndexInSheet=22|OwnerPartId=1|Location.X=1097|Location.X_Frac=50000|Location.Y=815|Corner.X=1097|Corner.X_Frac=50000|Corner.Y=805|LineWidth=1|Color=16711680
|RECORD=13|OwnerIndex=312|IsNotAccesible=T|IndexInSheet=23|OwnerPartId=1|Location.X=1092|Location.X_Frac=50000|Location.Y=815|Corner.X=1092|Corner.X_Frac=50000|Corner.Y=805|LineWidth=1|Color=16711680
|RECORD=41|OwnerIndex=312|IndexInSheet=24|OwnerPartId=-1|Location.X=1078|Location.Y=816|Color=8388608|FontID=1|IsHidden=T|Text=<VALENTIUM>|Name=VALENTIUM PART NUM
|RECORD=34|OwnerIndex=312|IndexInSheet=-1|OwnerPartId=-1|Location.X=1070|Location.Y=796|Color=8388608|FontID=1|Text=C45|Name=Designator|ReadOnlyState=1
|RECORD=41|OwnerIndex=312|IndexInSheet=-1|OwnerPartId=-1|Location.X=1078|Location.Y=816|Color=8388608|FontID=1|IsHidden=T|Text=CAP_0402_0.1UF_50V|Name=Comment|ReadOnlyState=1
|RECORD=44|OwnerIndex=312
|RECORD=45|OwnerIndex=342|IndexInSheet=-1|Description=Chip Capacitor, 0402, 2-Leads, Body 1.00x0.50mm, IPC Medium Density|UseComponentLibrary=T|ModelName=CAPC1005X06N|ModelType=PCBLIB|DatafileCount=1|ModelDatafileEntity0=CAPC1005X06N|ModelDatafileKind0=PCBLib|IsCurrent=T|DatalinksLocked=T|DatabaseDatalinksLocked=T|IntegratedModel=T|DatabaseModel=T
|RECORD=46|OwnerIndex=343
|RECORD=48|OwnerIndex=343
|RECORD=1|LibReference=CAP_0402_0.1UF_50V|ComponentDescription=CAP, CER, 0.1UF, 50V, 10%, X7R, AEC-Q200, 0402|PartCount=2|DisplayModeCount=1|IndexInSheet=42|OwnerPartId=-1|Location.X=1090|Location.Y=800|Orientation=1|CurrentPartId=1|LibraryPath=*|SourceLibraryName=Capacitors.IntLib|TargetFileName=*|AreaColor=11599871|Color=128|PartIDLocked=F|DesignItemId=CAP_0402_0.1UF_50V|AllPinCount=2
|RECORD=41|OwnerIndex=346|OwnerPartId=-1|Location.X=1038|Location.Y=826|Color=8388608|FontID=7|IsHidden=T|Text=CAP, CER|Name=CATEGORY
|RECORD=41|OwnerIndex=346|IndexInSheet=1|OwnerPartId=-1|Location.X=1038|Location.Y=826|Color=8388608|FontID=7|IsHidden=T|Text=TDK|Name=MFG NAME
|RECORD=41|OwnerIndex=346|IndexInSheet=2|OwnerPartId=-1|Location.X=1038|Location.Y=826|Color=8388608|FontID=7|IsHidden=T|Text=CGA2B3X7R1H104K050BB|Name=MFG PART NUM
|RECORD=41|OwnerIndex=346|IndexInSheet=3|OwnerPartId=-1|Location.X=1038|Location.Y=826|Color=8388608|FontID=7|IsHidden=T|Text=10/23/2013|Name=MODIFY DATE
|RECORD=41|OwnerIndex=346|IndexInSheet=4|OwnerPartId=-1|Location.X=1038|Location.Y=826|Color=8388608|FontID=7|IsHidden=T|Name=Date
|RECORD=41|OwnerIndex=346|IndexInSheet=5|OwnerPartId=-1|Location.X=1038|Location.Y=826|Color=8388608|FontID=7|IsHidden=T|Text=*|Name=SHEETPART
|RECORD=41|OwnerIndex=346|IndexInSheet=6|OwnerPartId=-1|Location.X=1038|Location.Y=826|Color=8388608|FontID=7|IsHidden=T|Text=10%|Name=P1
|RECORD=41|OwnerIndex=346|IndexInSheet=7|OwnerPartId=-1|Location.X=1038|Location.Y=826|Color=8388608|FontID=7|IsHidden=T|Text=125C|Name=MAXTEMP
|RECORD=41|OwnerIndex=346|IndexInSheet=8|OwnerPartId=-1|Location.X=1038|Location.Y=826|Color=8388608|FontID=7|IsHidden=T|Text=-55C|Name=MINTEMP
|RECORD=41|OwnerIndex=346|IndexInSheet=9|OwnerPartId=-1|Location.X=1038|Location.Y=826|Color=8388608|FontID=7|IsHidden=T|Text=AEC-Q200|Name=OTHER
|RECORD=41|OwnerIndex=346|IndexInSheet=10|OwnerPartId=-1|Location.X=1038|Location.Y=826|Color=8388608|FontID=7|IsHidden=T|Text=50V|Name=P2
|RECORD=41|OwnerIndex=346|IndexInSheet=11|OwnerPartId=-1|Location.X=1038|Location.Y=826|Color=8388608|FontID=7|IsHidden=T|Text=X7R|Name=P3
|RECORD=41|OwnerIndex=346|IndexInSheet=12|OwnerPartId=-1|Location.X=1038|Location.Y=826|Color=8388608|FontID=7|IsHidden=T|Text=0402|Name=Size
|RECORD=41|OwnerIndex=346|IndexInSheet=13|OwnerPartId=-1|Location.X=1038|Location.Y=826|Color=8388608|FontID=7|IsHidden=T|Name=SUB
|RECORD=41|OwnerIndex=346|IndexInSheet=14|OwnerPartId=-1|Location.X=1038|Location.Y=826|Color=8388608|FontID=1|IsHidden=T|Text=CAP, CER, 0.1UF, 50V, 10%, X7R, AEC-Q200, 0402|Name=DESC
|RECORD=41|OwnerIndex=346|IndexInSheet=15|OwnerPartId=-1|Location.X=1038|Location.Y=826|Color=8388608|FontID=1|IsHidden=T|Text=Digi-Key|Name=Supplier 1|ReadOnlyState=3
|RECORD=41|OwnerIndex=346|IndexInSheet=16|OwnerPartId=-1|Location.X=1038|Location.Y=826|Color=8388608|FontID=1|IsHidden=T|Text=445-6899-1-ND|Name=Supplier Part Number 1|ReadOnlyState=3
|RECORD=41|OwnerIndex=346|IndexInSheet=17|OwnerPartId=-1|Location.X=1060|Location.Y=820|Color=8388608|FontID=7|Text=0.1UF|Name=VALUE
|RECORD=2|OwnerIndex=346|OwnerPartId=1|FormalType=1|Electrical=4|PinConglomerate=32|PinLength=10|Location.X=1060|Location.Y=820|Name=2|Designator=2|SwapIdPin=2|SwapIDPart=1|PinPropagationDelay=0.000000E+000
|RECORD=2|OwnerIndex=346|OwnerPartId=1|FormalType=1|Electrical=4|PinConglomerate=34|PinLength=10|Location.X=1050|Location.Y=820|Name=1|Designator=1|SwapIdPin=1|SwapIDPart=1|PinPropagationDelay=0.000000E+000
|RECORD=13|OwnerIndex=346|IsNotAccesible=T|IndexInSheet=20|OwnerPartId=1|Location.X=1057|Location.X_Frac=50000|Location.Y=820|Corner.X=1060|Corner.Y=820|LineWidth=1|Color=16711680
|RECORD=13|OwnerIndex=346|IsNotAccesible=T|IndexInSheet=21|OwnerPartId=1|Location.X=1050|Location.Y=820|Corner.X=1052|Corner.X_Frac=50000|Corner.Y=820|LineWidth=1|Color=16711680
|RECORD=13|OwnerIndex=346|IsNotAccesible=T|IndexInSheet=22|OwnerPartId=1|Location.X=1057|Location.X_Frac=50000|Location.Y=825|Corner.X=1057|Corner.X_Frac=50000|Corner.Y=815|LineWidth=1|Color=16711680
|RECORD=13|OwnerIndex=346|IsNotAccesible=T|IndexInSheet=23|OwnerPartId=1|Location.X=1052|Location.X_Frac=50000|Location.Y=825|Corner.X=1052|Corner.X_Frac=50000|Corner.Y=815|LineWidth=1|Color=16711680
|RECORD=41|OwnerIndex=346|IndexInSheet=24|OwnerPartId=-1|Location.X=1038|Location.Y=826|Color=8388608|FontID=1|IsHidden=T|Text=<VALENTIUM>|Name=VALENTIUM PART NUM
|RECORD=34|OwnerIndex=346|IndexInSheet=-1|OwnerPartId=-1|Location.X=1030|Location.Y=820|Color=8388608|FontID=1|Text=C44|Name=Designator|ReadOnlyState=1
|RECORD=41|OwnerIndex=346|IndexInSheet=-1|OwnerPartId=-1|Location.X=1038|Location.Y=826|Color=8388608|FontID=1|IsHidden=T|Text=CAP_0402_0.1UF_50V|Name=Comment|ReadOnlyState=1
|RECORD=44|OwnerIndex=346
|RECORD=45|OwnerIndex=376|IndexInSheet=-1|Description=Chip Capacitor, 0402, 2-Leads, Body 1.00x0.50mm, IPC Medium Density|UseComponentLibrary=T|ModelName=CAPC1005X06N|ModelType=PCBLIB|DatafileCount=1|ModelDatafileEntity0=CAPC1005X06N|ModelDatafileKind0=PCBLib|IsCurrent=T|DatalinksLocked=T|DatabaseDatalinksLocked=T|IntegratedModel=T|DatabaseModel=T
|RECORD=46|OwnerIndex=377
|RECORD=48|OwnerIndex=377
|RECORD=1|LibReference=CAP_0402_0.1UF_50V|ComponentDescription=CAP, CER, 0.1UF, 50V, 10%, X7R, AEC-Q200, 0402|PartCount=2|DisplayModeCount=1|IndexInSheet=43|OwnerPartId=-1|Location.X=1060|Location.Y=770|Orientation=1|CurrentPartId=1|LibraryPath=*|SourceLibraryName=Capacitors.IntLib|TargetFileName=*|AreaColor=11599871|Color=128|PartIDLocked=F|DesignItemId=CAP_0402_0.1UF_50V|AllPinCount=2
|RECORD=41|OwnerIndex=380|OwnerPartId=-1|Location.X=1008|Location.Y=796|Color=8388608|FontID=7|IsHidden=T|Text=CAP, CER|Name=CATEGORY
|RECORD=41|OwnerIndex=380|IndexInSheet=1|OwnerPartId=-1|Location.X=1008|Location.Y=796|Color=8388608|FontID=7|IsHidden=T|Text=TDK|Name=MFG NAME
|RECORD=41|OwnerIndex=380|IndexInSheet=2|OwnerPartId=-1|Location.X=1008|Location.Y=796|Color=8388608|FontID=7|IsHidden=T|Text=CGA2B3X7R1H104K050BB|Name=MFG PART NUM
|RECORD=41|OwnerIndex=380|IndexInSheet=3|OwnerPartId=-1|Location.X=1008|Location.Y=796|Color=8388608|FontID=7|IsHidden=T|Text=10/23/2013|Name=MODIFY DATE
|RECORD=41|OwnerIndex=380|IndexInSheet=4|OwnerPartId=-1|Location.X=1008|Location.Y=796|Color=8388608|FontID=7|IsHidden=T|Name=Date
|RECORD=41|OwnerIndex=380|IndexInSheet=5|OwnerPartId=-1|Location.X=1008|Location.Y=796|Color=8388608|FontID=7|IsHidden=T|Text=*|Name=SHEETPART
|RECORD=41|OwnerIndex=380|IndexInSheet=6|OwnerPartId=-1|Location.X=1008|Location.Y=796|Color=8388608|FontID=7|IsHidden=T|Text=10%|Name=P1
|RECORD=41|OwnerIndex=380|IndexInSheet=7|OwnerPartId=-1|Location.X=1008|Location.Y=796|Color=8388608|FontID=7|IsHidden=T|Text=125C|Name=MAXTEMP
|RECORD=41|OwnerIndex=380|IndexInSheet=8|OwnerPartId=-1|Location.X=1008|Location.Y=796|Color=8388608|FontID=7|IsHidden=T|Text=-55C|Name=MINTEMP
|RECORD=41|OwnerIndex=380|IndexInSheet=9|OwnerPartId=-1|Location.X=1008|Location.Y=796|Color=8388608|FontID=7|IsHidden=T|Text=AEC-Q200|Name=OTHER
|RECORD=41|OwnerIndex=380|IndexInSheet=10|OwnerPartId=-1|Location.X=1008|Location.Y=796|Color=8388608|FontID=7|IsHidden=T|Text=50V|Name=P2
|RECORD=41|OwnerIndex=380|IndexInSheet=11|OwnerPartId=-1|Location.X=1008|Location.Y=796|Color=8388608|FontID=7|IsHidden=T|Text=X7R|Name=P3
|RECORD=41|OwnerIndex=380|IndexInSheet=12|OwnerPartId=-1|Location.X=1008|Location.Y=796|Color=8388608|FontID=7|IsHidden=T|Text=0402|Name=Size
|RECORD=41|OwnerIndex=380|IndexInSheet=13|OwnerPartId=-1|Location.X=1008|Location.Y=796|Color=8388608|FontID=7|IsHidden=T|Name=SUB
|RECORD=41|OwnerIndex=380|IndexInSheet=14|OwnerPartId=-1|Location.X=1008|Location.Y=796|Color=8388608|FontID=1|IsHidden=T|Text=CAP, CER, 0.1UF, 50V, 10%, X7R, AEC-Q200, 0402|Name=DESC
|RECORD=41|OwnerIndex=380|IndexInSheet=15|OwnerPartId=-1|Location.X=1008|Location.Y=796|Color=8388608|FontID=1|IsHidden=T|Text=Digi-Key|Name=Supplier 1|ReadOnlyState=3
|RECORD=41|OwnerIndex=380|IndexInSheet=16|OwnerPartId=-1|Location.X=1008|Location.Y=796|Color=8388608|FontID=1|IsHidden=T|Text=445-6899-1-ND|Name=Supplier Part Number 1|ReadOnlyState=3
|RECORD=41|OwnerIndex=380|IndexInSheet=17|OwnerPartId=-1|Location.X=1030|Location.Y=790|Color=8388608|FontID=7|Text=0.1UF|Name=VALUE
|RECORD=2|OwnerIndex=380|OwnerPartId=1|FormalType=1|Electrical=4|PinConglomerate=32|PinLength=10|Location.X=1030|Location.Y=790|Name=2|Designator=2|SwapIdPin=2|SwapIDPart=1|PinPropagationDelay=0.000000E+000
|RECORD=2|OwnerIndex=380|OwnerPartId=1|FormalType=1|Electrical=4|PinConglomerate=34|PinLength=10|Location.X=1020|Location.Y=790|Name=1|Designator=1|SwapIdPin=1|SwapIDPart=1|PinPropagationDelay=0.000000E+000
|RECORD=13|OwnerIndex=380|IsNotAccesible=T|IndexInSheet=20|OwnerPartId=1|Location.X=1027|Location.X_Frac=50000|Location.Y=790|Corner.X=1030|Corner.Y=790|LineWidth=1|Color=16711680
|RECORD=13|OwnerIndex=380|IsNotAccesible=T|IndexInSheet=21|OwnerPartId=1|Location.X=1020|Location.Y=790|Corner.X=1022|Corner.X_Frac=50000|Corner.Y=790|LineWidth=1|Color=16711680
|RECORD=13|OwnerIndex=380|IsNotAccesible=T|IndexInSheet=22|OwnerPartId=1|Location.X=1027|Location.X_Frac=50000|Location.Y=795|Corner.X=1027|Corner.X_Frac=50000|Corner.Y=785|LineWidth=1|Color=16711680
|RECORD=13|OwnerIndex=380|IsNotAccesible=T|IndexInSheet=23|OwnerPartId=1|Location.X=1022|Location.X_Frac=50000|Location.Y=795|Corner.X=1022|Corner.X_Frac=50000|Corner.Y=785|LineWidth=1|Color=16711680
|RECORD=41|OwnerIndex=380|IndexInSheet=24|OwnerPartId=-1|Location.X=1008|Location.Y=796|Color=8388608|FontID=1|IsHidden=T|Text=<VALENTIUM>|Name=VALENTIUM PART NUM
|RECORD=34|OwnerIndex=380|IndexInSheet=-1|OwnerPartId=-1|Location.X=1000|Location.Y=790|Color=8388608|FontID=1|Text=C46|Name=Designator|ReadOnlyState=1
|RECORD=41|OwnerIndex=380|IndexInSheet=-1|OwnerPartId=-1|Location.X=1008|Location.Y=796|Color=8388608|FontID=1|IsHidden=T|Text=CAP_0402_0.1UF_50V|Name=Comment|ReadOnlyState=1
|RECORD=44|OwnerIndex=380
|RECORD=45|OwnerIndex=410|IndexInSheet=-1|Description=Chip Capacitor, 0402, 2-Leads, Body 1.00x0.50mm, IPC Medium Density|UseComponentLibrary=T|ModelName=CAPC1005X06N|ModelType=PCBLIB|DatafileCount=1|ModelDatafileEntity0=CAPC1005X06N|ModelDatafileKind0=PCBLib|IsCurrent=T|DatalinksLocked=T|DatabaseDatalinksLocked=T|IntegratedModel=T|DatabaseModel=T
|RECORD=46|OwnerIndex=411
|RECORD=48|OwnerIndex=411
|RECORD=1|LibReference=CAP_0402_0.1UF_50V|ComponentDescription=CAP, CER, 0.1UF, 50V, 10%, X7R, AEC-Q200, 0402|PartCount=2|DisplayModeCount=1|IndexInSheet=44|OwnerPartId=-1|Location.X=1090|Location.Y=720|Orientation=1|CurrentPartId=1|LibraryPath=*|SourceLibraryName=Capacitors.IntLib|TargetFileName=*|AreaColor=11599871|Color=128|PartIDLocked=F|DesignItemId=CAP_0402_0.1UF_50V|AllPinCount=2
|RECORD=41|OwnerIndex=414|OwnerPartId=-1|Location.X=1038|Location.Y=746|Color=8388608|FontID=7|IsHidden=T|Text=CAP, CER|Name=CATEGORY
|RECORD=41|OwnerIndex=414|IndexInSheet=1|OwnerPartId=-1|Location.X=1038|Location.Y=746|Color=8388608|FontID=7|IsHidden=T|Text=TDK|Name=MFG NAME
|RECORD=41|OwnerIndex=414|IndexInSheet=2|OwnerPartId=-1|Location.X=1038|Location.Y=746|Color=8388608|FontID=7|IsHidden=T|Text=CGA2B3X7R1H104K050BB|Name=MFG PART NUM
|RECORD=41|OwnerIndex=414|IndexInSheet=3|OwnerPartId=-1|Location.X=1038|Location.Y=746|Color=8388608|FontID=7|IsHidden=T|Text=10/23/2013|Name=MODIFY DATE
|RECORD=41|OwnerIndex=414|IndexInSheet=4|OwnerPartId=-1|Location.X=1038|Location.Y=746|Color=8388608|FontID=7|IsHidden=T|Name=Date
|RECORD=41|OwnerIndex=414|IndexInSheet=5|OwnerPartId=-1|Location.X=1038|Location.Y=746|Color=8388608|FontID=7|IsHidden=T|Text=*|Name=SHEETPART
|RECORD=41|OwnerIndex=414|IndexInSheet=6|OwnerPartId=-1|Location.X=1038|Location.Y=746|Color=8388608|FontID=7|IsHidden=T|Text=10%|Name=P1
|RECORD=41|OwnerIndex=414|IndexInSheet=7|OwnerPartId=-1|Location.X=1038|Location.Y=746|Color=8388608|FontID=7|IsHidden=T|Text=125C|Name=MAXTEMP
|RECORD=41|OwnerIndex=414|IndexInSheet=8|OwnerPartId=-1|Location.X=1038|Location.Y=746|Color=8388608|FontID=7|IsHidden=T|Text=-55C|Name=MINTEMP
|RECORD=41|OwnerIndex=414|IndexInSheet=9|OwnerPartId=-1|Location.X=1038|Location.Y=746|Color=8388608|FontID=7|IsHidden=T|Text=AEC-Q200|Name=OTHER
|RECORD=41|OwnerIndex=414|IndexInSheet=10|OwnerPartId=-1|Location.X=1038|Location.Y=746|Color=8388608|FontID=7|IsHidden=T|Text=50V|Name=P2
|RECORD=41|OwnerIndex=414|IndexInSheet=11|OwnerPartId=-1|Location.X=1038|Location.Y=746|Color=8388608|FontID=7|IsHidden=T|Text=X7R|Name=P3
|RECORD=41|OwnerIndex=414|IndexInSheet=12|OwnerPartId=-1|Location.X=1038|Location.Y=746|Color=8388608|FontID=7|IsHidden=T|Text=0402|Name=Size
|RECORD=41|OwnerIndex=414|IndexInSheet=13|OwnerPartId=-1|Location.X=1038|Location.Y=746|Color=8388608|FontID=7|IsHidden=T|Name=SUB
|RECORD=41|OwnerIndex=414|IndexInSheet=14|OwnerPartId=-1|Location.X=1038|Location.Y=746|Color=8388608|FontID=1|IsHidden=T|Text=CAP, CER, 0.1UF, 50V, 10%, X7R, AEC-Q200, 0402|Name=DESC
|RECORD=41|OwnerIndex=414|IndexInSheet=15|OwnerPartId=-1|Location.X=1038|Location.Y=746|Color=8388608|FontID=1|IsHidden=T|Text=Digi-Key|Name=Supplier 1|ReadOnlyState=3
|RECORD=41|OwnerIndex=414|IndexInSheet=16|OwnerPartId=-1|Location.X=1038|Location.Y=746|Color=8388608|FontID=1|IsHidden=T|Text=445-6899-1-ND|Name=Supplier Part Number 1|ReadOnlyState=3
|RECORD=41|OwnerIndex=414|IndexInSheet=17|OwnerPartId=-1|Location.X=1060|Location.Y=740|Color=8388608|FontID=7|Text=0.1UF|Name=VALUE
|RECORD=2|OwnerIndex=414|OwnerPartId=1|FormalType=1|Electrical=4|PinConglomerate=32|PinLength=10|Location.X=1060|Location.Y=740|Name=2|Designator=2|SwapIdPin=2|SwapIDPart=1|PinPropagationDelay=0.000000E+000
|RECORD=2|OwnerIndex=414|OwnerPartId=1|FormalType=1|Electrical=4|PinConglomerate=34|PinLength=10|Location.X=1050|Location.Y=740|Name=1|Designator=1|SwapIdPin=1|SwapIDPart=1|PinPropagationDelay=0.000000E+000
|RECORD=13|OwnerIndex=414|IsNotAccesible=T|IndexInSheet=20|OwnerPartId=1|Location.X=1057|Location.X_Frac=50000|Location.Y=740|Corner.X=1060|Corner.Y=740|LineWidth=1|Color=16711680
|RECORD=13|OwnerIndex=414|IsNotAccesible=T|IndexInSheet=21|OwnerPartId=1|Location.X=1050|Location.Y=740|Corner.X=1052|Corner.X_Frac=50000|Corner.Y=740|LineWidth=1|Color=16711680
|RECORD=13|OwnerIndex=414|IsNotAccesible=T|IndexInSheet=22|OwnerPartId=1|Location.X=1057|Location.X_Frac=50000|Location.Y=745|Corner.X=1057|Corner.X_Frac=50000|Corner.Y=735|LineWidth=1|Color=16711680
|RECORD=13|OwnerIndex=414|IsNotAccesible=T|IndexInSheet=23|OwnerPartId=1|Location.X=1052|Location.X_Frac=50000|Location.Y=745|Corner.X=1052|Corner.X_Frac=50000|Corner.Y=735|LineWidth=1|Color=16711680
|RECORD=41|OwnerIndex=414|IndexInSheet=24|OwnerPartId=-1|Location.X=1038|Location.Y=746|Color=8388608|FontID=1|IsHidden=T|Text=<VALENTIUM>|Name=VALENTIUM PART NUM
|RECORD=34|OwnerIndex=414|IndexInSheet=-1|OwnerPartId=-1|Location.X=1030|Location.Y=740|Color=8388608|FontID=1|Text=C48|Name=Designator|ReadOnlyState=1
|RECORD=41|OwnerIndex=414|IndexInSheet=-1|OwnerPartId=-1|Location.X=1038|Location.Y=746|Color=8388608|FontID=1|IsHidden=T|Text=CAP_0402_0.1UF_50V|Name=Comment|ReadOnlyState=1
|RECORD=44|OwnerIndex=414
|RECORD=45|OwnerIndex=444|IndexInSheet=-1|Description=Chip Capacitor, 0402, 2-Leads, Body 1.00x0.50mm, IPC Medium Density|UseComponentLibrary=T|ModelName=CAPC1005X06N|ModelType=PCBLIB|DatafileCount=1|ModelDatafileEntity0=CAPC1005X06N|ModelDatafileKind0=PCBLib|IsCurrent=T|DatalinksLocked=T|DatabaseDatalinksLocked=T|IntegratedModel=T|DatabaseModel=T
|RECORD=46|OwnerIndex=445
|RECORD=48|OwnerIndex=445
|RECORD=1|LibReference=CAP_0402_0.1UF_50V|ComponentDescription=CAP, CER, 0.1UF, 50V, 10%, X7R, AEC-Q200, 0402|PartCount=2|DisplayModeCount=1|IndexInSheet=45|OwnerPartId=-1|Location.X=1090|Location.Y=680|Orientation=1|CurrentPartId=1|LibraryPath=*|SourceLibraryName=Capacitors.IntLib|TargetFileName=*|AreaColor=11599871|Color=128|PartIDLocked=F|DesignItemId=CAP_0402_0.1UF_50V|AllPinCount=2
|RECORD=41|OwnerIndex=448|OwnerPartId=-1|Location.X=1038|Location.Y=706|Color=8388608|FontID=7|IsHidden=T|Text=CAP, CER|Name=CATEGORY
|RECORD=41|OwnerIndex=448|IndexInSheet=1|OwnerPartId=-1|Location.X=1038|Location.Y=706|Color=8388608|FontID=7|IsHidden=T|Text=TDK|Name=MFG NAME
|RECORD=41|OwnerIndex=448|IndexInSheet=2|OwnerPartId=-1|Location.X=1038|Location.Y=706|Color=8388608|FontID=7|IsHidden=T|Text=CGA2B3X7R1H104K050BB|Name=MFG PART NUM
|RECORD=41|OwnerIndex=448|IndexInSheet=3|OwnerPartId=-1|Location.X=1038|Location.Y=706|Color=8388608|FontID=7|IsHidden=T|Text=10/23/2013|Name=MODIFY DATE
|RECORD=41|OwnerIndex=448|IndexInSheet=4|OwnerPartId=-1|Location.X=1038|Location.Y=706|Color=8388608|FontID=7|IsHidden=T|Name=Date
|RECORD=41|OwnerIndex=448|IndexInSheet=5|OwnerPartId=-1|Location.X=1038|Location.Y=706|Color=8388608|FontID=7|IsHidden=T|Text=*|Name=SHEETPART
|RECORD=41|OwnerIndex=448|IndexInSheet=6|OwnerPartId=-1|Location.X=1038|Location.Y=706|Color=8388608|FontID=7|IsHidden=T|Text=10%|Name=P1
|RECORD=41|OwnerIndex=448|IndexInSheet=7|OwnerPartId=-1|Location.X=1038|Location.Y=706|Color=8388608|FontID=7|IsHidden=T|Text=125C|Name=MAXTEMP
|RECORD=41|OwnerIndex=448|IndexInSheet=8|OwnerPartId=-1|Location.X=1038|Location.Y=706|Color=8388608|FontID=7|IsHidden=T|Text=-55C|Name=MINTEMP
|RECORD=41|OwnerIndex=448|IndexInSheet=9|OwnerPartId=-1|Location.X=1038|Location.Y=706|Color=8388608|FontID=7|IsHidden=T|Text=AEC-Q200|Name=OTHER
|RECORD=41|OwnerIndex=448|IndexInSheet=10|OwnerPartId=-1|Location.X=1038|Location.Y=706|Color=8388608|FontID=7|IsHidden=T|Text=50V|Name=P2
|RECORD=41|OwnerIndex=448|IndexInSheet=11|OwnerPartId=-1|Location.X=1038|Location.Y=706|Color=8388608|FontID=7|IsHidden=T|Text=X7R|Name=P3
|RECORD=41|OwnerIndex=448|IndexInSheet=12|OwnerPartId=-1|Location.X=1038|Location.Y=706|Color=8388608|FontID=7|IsHidden=T|Text=0402|Name=Size
|RECORD=41|OwnerIndex=448|IndexInSheet=13|OwnerPartId=-1|Location.X=1038|Location.Y=706|Color=8388608|FontID=7|IsHidden=T|Name=SUB
|RECORD=41|OwnerIndex=448|IndexInSheet=14|OwnerPartId=-1|Location.X=1038|Location.Y=706|Color=8388608|FontID=1|IsHidden=T|Text=CAP, CER, 0.1UF, 50V, 10%, X7R, AEC-Q200, 0402|Name=DESC
|RECORD=41|OwnerIndex=448|IndexInSheet=15|OwnerPartId=-1|Location.X=1038|Location.Y=706|Color=8388608|FontID=1|IsHidden=T|Text=Digi-Key|Name=Supplier 1|ReadOnlyState=3
|RECORD=41|OwnerIndex=448|IndexInSheet=16|OwnerPartId=-1|Location.X=1038|Location.Y=706|Color=8388608|FontID=1|IsHidden=T|Text=445-6899-1-ND|Name=Supplier Part Number 1|ReadOnlyState=3
|RECORD=41|OwnerIndex=448|IndexInSheet=17|OwnerPartId=-1|Location.X=1060|Location.Y=700|Color=8388608|FontID=7|Text=0.1UF|Name=VALUE
|RECORD=2|OwnerIndex=448|OwnerPartId=1|FormalType=1|Electrical=4|PinConglomerate=32|PinLength=10|Location.X=1060|Location.Y=700|Name=2|Designator=2|SwapIdPin=2|SwapIDPart=1|PinPropagationDelay=0.000000E+000
|RECORD=2|OwnerIndex=448|OwnerPartId=1|FormalType=1|Electrical=4|PinConglomerate=34|PinLength=10|Location.X=1050|Location.Y=700|Name=1|Designator=1|SwapIdPin=1|SwapIDPart=1|PinPropagationDelay=0.000000E+000
|RECORD=13|OwnerIndex=448|IsNotAccesible=T|IndexInSheet=20|OwnerPartId=1|Location.X=1057|Location.X_Frac=50000|Location.Y=700|Corner.X=1060|Corner.Y=700|LineWidth=1|Color=16711680
|RECORD=13|OwnerIndex=448|IsNotAccesible=T|IndexInSheet=21|OwnerPartId=1|Location.X=1050|Location.Y=700|Corner.X=1052|Corner.X_Frac=50000|Corner.Y=700|LineWidth=1|Color=16711680
|RECORD=13|OwnerIndex=448|IsNotAccesible=T|IndexInSheet=22|OwnerPartId=1|Location.X=1057|Location.X_Frac=50000|Location.Y=705|Corner.X=1057|Corner.X_Frac=50000|Corner.Y=695|LineWidth=1|Color=16711680
|RECORD=13|OwnerIndex=448|IsNotAccesible=T|IndexInSheet=23|OwnerPartId=1|Location.X=1052|Location.X_Frac=50000|Location.Y=705|Corner.X=1052|Corner.X_Frac=50000|Corner.Y=695|LineWidth=1|Color=16711680
|RECORD=41|OwnerIndex=448|IndexInSheet=24|OwnerPartId=-1|Location.X=1038|Location.Y=706|Color=8388608|FontID=1|IsHidden=T|Text=<VALENTIUM>|Name=VALENTIUM PART NUM
|RECORD=34|OwnerIndex=448|IndexInSheet=-1|OwnerPartId=-1|Location.X=1030|Location.Y=700|Color=8388608|FontID=1|Text=C50|Name=Designator|ReadOnlyState=1
|RECORD=41|OwnerIndex=448|IndexInSheet=-1|OwnerPartId=-1|Location.X=1038|Location.Y=706|Color=8388608|FontID=1|IsHidden=T|Text=CAP_0402_0.1UF_50V|Name=Comment|ReadOnlyState=1
|RECORD=44|OwnerIndex=448
|RECORD=45|OwnerIndex=478|IndexInSheet=-1|Description=Chip Capacitor, 0402, 2-Leads, Body 1.00x0.50mm, IPC Medium Density|UseComponentLibrary=T|ModelName=CAPC1005X06N|ModelType=PCBLIB|DatafileCount=1|ModelDatafileEntity0=CAPC1005X06N|ModelDatafileKind0=PCBLib|IsCurrent=T|DatalinksLocked=T|DatabaseDatalinksLocked=T|IntegratedModel=T|DatabaseModel=T
|RECORD=46|OwnerIndex=479
|RECORD=48|OwnerIndex=479
|RECORD=1|LibReference=PCIex4|ComponentDescription=PCIE x4 Edge Connector,OrCAD Symbol,NC|PartCount=2|DisplayModeCount=1|IndexInSheet=46|OwnerPartId=-1|Location.X=770|Location.Y=960|CurrentPartId=1|LibraryPath=*|SourceLibraryName=Connectors.IntLib|TargetFileName=*|AreaColor=11599871|Color=128|PartIDLocked=T|DesignItemId=PCIex4|AllPinCount=64
|RECORD=41|OwnerIndex=482|OwnerPartId=1|Location.X=90|Location.Y=150|Color=8388608|FontID=1|IsHidden=T|Text=NC|Name=NOTE|NotAutoPosition=T
|RECORD=41|OwnerIndex=482|IndexInSheet=1|OwnerPartId=1|Location.X=90|Location.Y=150|Color=8388608|FontID=1|IsHidden=T|Text=451|Name=Part Number|NotAutoPosition=T
|RECORD=41|OwnerIndex=482|IndexInSheet=2|OwnerPartId=1|Location.X=90|Location.Y=150|Color=8388608|FontID=1|IsHidden=T|Text=NA|Name=Manufacturer|NotAutoPosition=T
|RECORD=41|OwnerIndex=482|IndexInSheet=3|OwnerPartId=1|Location.X=90|Location.Y=150|Color=8388608|FontID=1|IsHidden=T|Text=NA|Name=Vendor P/N|NotAutoPosition=T
|RECORD=41|OwnerIndex=482|IndexInSheet=4|OwnerPartId=1|Location.X=90|Location.Y=150|Color=8388608|FontID=1|IsHidden=T|Text=SMT|Name=Part Type|NotAutoPosition=T
|RECORD=4|OwnerIndex=482|IsNotAccesible=T|IndexInSheet=5|OwnerPartId=1|Location.X=774|Location.Y=837|Color=8388608|FontID=9|Text=KEY
|RECORD=4|OwnerIndex=482|IsNotAccesible=T|IndexInSheet=6|OwnerPartId=1|Location.X=890|Location.Y=838|Color=8388608|FontID=9|Text=KEY
|RECORD=14|OwnerIndex=482|IsNotAccesible=T|IndexInSheet=7|OwnerPartId=1|Location.X=770|Location.Y=620|Corner.X=910|Corner.Y=960|LineWidth=1|Color=128|AreaColor=11599871|IsSolid=T|Transparent=T
|RECORD=2|OwnerIndex=482|OwnerPartId=1|FormalType=1|Electrical=7|PinConglomerate=58|PinLength=10|Location.X=770|Location.Y=950|Name=+12v1|Designator=B1|SwapIDPart=Ž&Ž||PinPropagationDelay=0.000000E+000
|RECORD=2|OwnerIndex=482|OwnerPartId=1|FormalType=1|Electrical=7|PinConglomerate=58|PinLength=10|Location.X=770|Location.Y=940|Name=+12V2|Designator=B2|SwapIDPart=Ž&Ž||PinPropagationDelay=0.000000E+000
|RECORD=2|OwnerIndex=482|OwnerPartId=1|FormalType=1|Electrical=7|PinConglomerate=58|PinLength=10|Location.X=770|Location.Y=930|Name=+12V3|Designator=B3|SwapIDPart=Ž&Ž||PinPropagationDelay=0.000000E+000
|RECORD=2|OwnerIndex=482|OwnerPartId=1|FormalType=1|Electrical=7|PinConglomerate=58|PinLength=10|Location.X=770|Location.Y=920|Name=GND1|Designator=B4|SwapIDPart=Ž&Ž||PinPropagationDelay=0.000000E+000
|RECORD=2|OwnerIndex=482|OwnerPartId=1|FormalType=1|Electrical=4|PinConglomerate=58|PinLength=10|Location.X=770|Location.Y=910|Name=SMCLK|Designator=B5|SwapIDPart=Ž&Ž||PinPropagationDelay=0.000000E+000
|RECORD=2|OwnerIndex=482|OwnerPartId=1|FormalType=1|Electrical=4|PinConglomerate=58|PinLength=10|Location.X=770|Location.Y=900|Name=SMDATA|Designator=B6|SwapIDPart=Ž&Ž||PinPropagationDelay=0.000000E+000
|RECORD=2|OwnerIndex=482|OwnerPartId=1|FormalType=1|Electrical=7|PinConglomerate=58|PinLength=10|Location.X=770|Location.Y=890|Name=GND2|Designator=B7|SwapIDPart=Ž&Ž||PinPropagationDelay=0.000000E+000
|RECORD=2|OwnerIndex=482|OwnerPartId=1|FormalType=1|Electrical=7|PinConglomerate=58|PinLength=10|Location.X=770|Location.Y=880|Name=+3.3V1|Designator=B8|SwapIDPart=Ž&Ž||PinPropagationDelay=0.000000E+000
|RECORD=2|OwnerIndex=482|OwnerPartId=1|FormalType=1|Electrical=4|PinConglomerate=58|PinLength=10|Location.X=770|Location.Y=870|Name=JTAG/TRST_n|Designator=B9|SwapIDPart=Ž&Ž||PinPropagationDelay=0.000000E+000
|RECORD=2|OwnerIndex=482|OwnerPartId=1|FormalType=1|Electrical=4|PinConglomerate=58|PinLength=10|Location.X=770|Location.Y=860|Name=+3.3vaux|Designator=B10|SwapIDPart=Ž&Ž||PinPropagationDelay=0.000000E+000
|RECORD=2|OwnerIndex=482|OwnerPartId=1|FormalType=1|Electrical=4|PinConglomerate=58|PinLength=10|Location.X=770|Location.Y=850|Name=WAKE_n|Designator=B11|SwapIDPart=Ž&Ž||PinPropagationDelay=0.000000E+000
|RECORD=2|OwnerIndex=482|OwnerPartId=1|FormalType=1|Electrical=4|PinConglomerate=58|PinLength=10|Location.X=770|Location.Y=830|Name=RESERVED1|Designator=B12|SwapIDPart=Ž&Ž||PinPropagationDelay=0.000000E+000
|RECORD=2|OwnerIndex=482|OwnerPartId=1|FormalType=1|Electrical=7|PinConglomerate=58|PinLength=10|Location.X=770|Location.Y=820|Name=GND3|Designator=B13|SwapIDPart=Ž&Ž||PinPropagationDelay=0.000000E+000
|RECORD=2|OwnerIndex=482|OwnerPartId=1|FormalType=1|Electrical=4|PinConglomerate=58|PinLength=10|Location.X=770|Location.Y=810|Name=PETp0|Designator=B14|SwapIDPart=Ž&Ž||PinPropagationDelay=0.000000E+000
|RECORD=2|OwnerIndex=482|OwnerPartId=1|FormalType=1|Electrical=4|PinConglomerate=58|PinLength=10|Location.X=770|Location.Y=800|Name=PETn0|Designator=B15|SwapIDPart=Ž&Ž||PinPropagationDelay=0.000000E+000
|RECORD=2|OwnerIndex=482|OwnerPartId=1|FormalType=1|Electrical=7|PinConglomerate=58|PinLength=10|Location.X=770|Location.Y=790|Name=GND4|Designator=B16|SwapIDPart=Ž&Ž||PinPropagationDelay=0.000000E+000
|RECORD=2|OwnerIndex=482|OwnerPartId=1|FormalType=1|Electrical=4|PinConglomerate=58|PinLength=10|Location.X=770|Location.Y=780|Name=PRSNT2_n|Designator=B17|SwapIDPart=Ž&Ž||PinPropagationDelay=0.000000E+000
|RECORD=2|OwnerIndex=482|OwnerPartId=1|FormalType=1|Electrical=7|PinConglomerate=58|PinLength=10|Location.X=770|Location.Y=770|Name=GND5|Designator=B18|SwapIDPart=Ž&Ž||PinPropagationDelay=0.000000E+000
|RECORD=2|OwnerIndex=482|OwnerPartId=1|FormalType=1|Electrical=4|PinConglomerate=58|PinLength=10|Location.X=770|Location.Y=760|Name=PETp1|Designator=B19|SwapIDPart=Ž&Ž||PinPropagationDelay=0.000000E+000
|RECORD=2|OwnerIndex=482|OwnerPartId=1|FormalType=1|Electrical=4|PinConglomerate=58|PinLength=10|Location.X=770|Location.Y=750|Name=PETn1|Designator=B20|SwapIDPart=Ž&Ž||PinPropagationDelay=0.000000E+000
|RECORD=2|OwnerIndex=482|OwnerPartId=1|FormalType=1|Electrical=7|PinConglomerate=58|PinLength=10|Location.X=770|Location.Y=740|Name=GND6|Designator=B21|SwapIDPart=Ž&Ž||PinPropagationDelay=0.000000E+000
|RECORD=2|OwnerIndex=482|OwnerPartId=1|FormalType=1|Electrical=7|PinConglomerate=58|PinLength=10|Location.X=770|Location.Y=730|Name=GND7|Designator=B22|SwapIDPart=Ž&Ž||PinPropagationDelay=0.000000E+000
|RECORD=2|OwnerIndex=482|OwnerPartId=1|FormalType=1|Electrical=4|PinConglomerate=58|PinLength=10|Location.X=770|Location.Y=720|Name=PETp2|Designator=B23|SwapIDPart=Ž&Ž||PinPropagationDelay=0.000000E+000
|RECORD=2|OwnerIndex=482|OwnerPartId=1|FormalType=1|Electrical=4|PinConglomerate=58|PinLength=10|Location.X=770|Location.Y=710|Name=PETn2|Designator=B24|SwapIDPart=Ž&Ž||PinPropagationDelay=0.000000E+000
|RECORD=2|OwnerIndex=482|OwnerPartId=1|FormalType=1|Electrical=7|PinConglomerate=58|PinLength=10|Location.X=770|Location.Y=700|Name=GND8|Designator=B25|SwapIDPart=Ž&Ž||PinPropagationDelay=0.000000E+000
|RECORD=2|OwnerIndex=482|OwnerPartId=1|FormalType=1|Electrical=7|PinConglomerate=58|PinLength=10|Location.X=770|Location.Y=690|Name=GND9|Designator=B26|SwapIDPart=Ž&Ž||PinPropagationDelay=0.000000E+000
|RECORD=2|OwnerIndex=482|OwnerPartId=1|FormalType=1|Electrical=4|PinConglomerate=58|PinLength=10|Location.X=770|Location.Y=680|Name=PETp3|Designator=B27|SwapIDPart=Ž&Ž||PinPropagationDelay=0.000000E+000
|RECORD=2|OwnerIndex=482|OwnerPartId=1|FormalType=1|Electrical=4|PinConglomerate=58|PinLength=10|Location.X=770|Location.Y=670|Name=PETn3|Designator=B28|SwapIDPart=Ž&Ž||PinPropagationDelay=0.000000E+000
|RECORD=2|OwnerIndex=482|OwnerPartId=1|FormalType=1|Electrical=7|PinConglomerate=58|PinLength=10|Location.X=770|Location.Y=660|Name=GND10|Designator=B29|SwapIDPart=Ž&Ž||PinPropagationDelay=0.000000E+000
|RECORD=2|OwnerIndex=482|OwnerPartId=1|FormalType=1|Electrical=4|PinConglomerate=58|PinLength=10|Location.X=770|Location.Y=650|Name=RESERVED2|Designator=B30|SwapIDPart=Ž&Ž||PinPropagationDelay=0.000000E+000
|RECORD=2|OwnerIndex=482|OwnerPartId=1|FormalType=1|Electrical=4|PinConglomerate=58|PinLength=10|Location.X=770|Location.Y=640|Name=PRSNT4_n|Designator=B31|SwapIDPart=Ž&Ž||PinPropagationDelay=0.000000E+000
|RECORD=2|OwnerIndex=482|OwnerPartId=1|FormalType=1|Electrical=7|PinConglomerate=58|PinLength=10|Location.X=770|Location.Y=630|Name=GND11|Designator=B32|SwapIDPart=Ž&Ž||PinPropagationDelay=0.000000E+000
|RECORD=2|OwnerIndex=482|OwnerPartId=1|FormalType=1|Electrical=4|PinConglomerate=56|PinLength=10|Location.X=910|Location.Y=950|Name=PRSNT1_n|Designator=A1|SwapIDPart=Ž&Ž||PinPropagationDelay=0.000000E+000
|RECORD=2|OwnerIndex=482|OwnerPartId=1|FormalType=1|Electrical=4|PinConglomerate=56|PinLength=10|Location.X=910|Location.Y=940|Name=+12V5|Designator=A2|SwapIDPart=Ž&Ž||PinPropagationDelay=0.000000E+000
|RECORD=2|OwnerIndex=482|OwnerPartId=1|FormalType=1|Electrical=4|PinConglomerate=56|PinLength=10|Location.X=910|Location.Y=930|Name=+12V4|Designator=A3|SwapIDPart=Ž&Ž||PinPropagationDelay=0.000000E+000
|RECORD=2|OwnerIndex=482|OwnerPartId=1|FormalType=1|Electrical=7|PinConglomerate=56|PinLength=10|Location.X=910|Location.Y=920|Name=GND37|Designator=A4|SwapIDPart=Ž&Ž||PinPropagationDelay=0.000000E+000
|RECORD=2|OwnerIndex=482|OwnerPartId=1|FormalType=1|Electrical=4|PinConglomerate=56|PinLength=10|Location.X=910|Location.Y=910|Name=JTAG/TCK|Designator=A5|SwapIDPart=Ž&Ž||PinPropagationDelay=0.000000E+000
|RECORD=2|OwnerIndex=482|OwnerPartId=1|FormalType=1|Electrical=4|PinConglomerate=56|PinLength=10|Location.X=910|Location.Y=900|Name=JTAG/TDI|Designator=A6|SwapIDPart=Ž&Ž||PinPropagationDelay=0.000000E+000
|RECORD=2|OwnerIndex=482|OwnerPartId=1|FormalType=1|Electrical=4|PinConglomerate=56|PinLength=10|Location.X=910|Location.Y=890|Name=JTAG/TDO|Designator=A7|SwapIDPart=Ž&Ž||PinPropagationDelay=0.000000E+000
|RECORD=2|OwnerIndex=482|OwnerPartId=1|FormalType=1|Electrical=4|PinConglomerate=56|PinLength=10|Location.X=910|Location.Y=880|Name=JTAG/TMS|Designator=A8|SwapIDPart=Ž&Ž||PinPropagationDelay=0.000000E+000
|RECORD=2|OwnerIndex=482|OwnerPartId=1|FormalType=1|Electrical=4|PinConglomerate=56|PinLength=10|Location.X=910|Location.Y=870|Name=+3.3V3|Designator=A9|SwapIDPart=Ž&Ž||PinPropagationDelay=0.000000E+000
|RECORD=2|OwnerIndex=482|OwnerPartId=1|FormalType=1|Electrical=4|PinConglomerate=56|PinLength=10|Location.X=910|Location.Y=860|Name=+3.3V2|Designator=A10|SwapIDPart=Ž&Ž||PinPropagationDelay=0.000000E+000
|RECORD=2|OwnerIndex=482|OwnerPartId=1|FormalType=1|Electrical=4|PinConglomerate=56|PinLength=10|Location.X=910|Location.Y=850|Name=PERST|Designator=A11|SwapIDPart=Ž&Ž||PinPropagationDelay=0.000000E+000
|RECORD=2|OwnerIndex=482|OwnerPartId=1|FormalType=1|Electrical=7|PinConglomerate=56|PinLength=10|Location.X=910|Location.Y=830|Name=GND36|Designator=A12|SwapIDPart=Ž&Ž||PinPropagationDelay=0.000000E+000
|RECORD=2|OwnerIndex=482|OwnerPartId=1|FormalType=1|Electrical=4|PinConglomerate=56|PinLength=10|Location.X=910|Location.Y=820|Name=REFCLK+|Designator=A13|SwapIDPart=Ž&Ž||PinPropagationDelay=0.000000E+000
|RECORD=2|OwnerIndex=482|OwnerPartId=1|FormalType=1|Electrical=4|PinConglomerate=56|PinLength=10|Location.X=910|Location.Y=810|Name=REFCLK-|Designator=A14|SwapIDPart=Ž&Ž||PinPropagationDelay=0.000000E+000
|RECORD=2|OwnerIndex=482|OwnerPartId=1|FormalType=1|Electrical=7|PinConglomerate=56|PinLength=10|Location.X=910|Location.Y=800|Name=GND35|Designator=A15|SwapIDPart=Ž&Ž||PinPropagationDelay=0.000000E+000
|RECORD=2|OwnerIndex=482|OwnerPartId=1|FormalType=1|Electrical=4|PinConglomerate=56|PinLength=10|Location.X=910|Location.Y=790|Name=PERp0|Designator=A16|SwapIDPart=Ž&Ž||PinPropagationDelay=0.000000E+000
|RECORD=2|OwnerIndex=482|OwnerPartId=1|FormalType=1|Electrical=4|PinConglomerate=56|PinLength=10|Location.X=910|Location.Y=780|Name=PERn0|Designator=A17|SwapIDPart=Ž&Ž||PinPropagationDelay=0.000000E+000
|RECORD=2|OwnerIndex=482|OwnerPartId=1|FormalType=1|Electrical=7|PinConglomerate=56|PinLength=10|Location.X=910|Location.Y=770|Name=GND34|Designator=A18|SwapIDPart=Ž&Ž||PinPropagationDelay=0.000000E+000
|RECORD=2|OwnerIndex=482|OwnerPartId=1|FormalType=1|Electrical=4|PinConglomerate=56|PinLength=10|Location.X=910|Location.Y=760|Name=RESERVED5|Designator=A19|SwapIDPart=Ž&Ž||PinPropagationDelay=0.000000E+000
|RECORD=2|OwnerIndex=482|OwnerPartId=1|FormalType=1|Electrical=7|PinConglomerate=56|PinLength=10|Location.X=910|Location.Y=750|Name=GND33|Designator=A20|SwapIDPart=Ž&Ž||PinPropagationDelay=0.000000E+000
|RECORD=2|OwnerIndex=482|OwnerPartId=1|FormalType=1|Electrical=4|PinConglomerate=56|PinLength=10|Location.X=910|Location.Y=740|Name=PERp1|Designator=A21|SwapIDPart=Ž&Ž||PinPropagationDelay=0.000000E+000
|RECORD=2|OwnerIndex=482|OwnerPartId=1|FormalType=1|Electrical=4|PinConglomerate=56|PinLength=10|Location.X=910|Location.Y=730|Name=PERn1|Designator=A22|SwapIDPart=Ž&Ž||PinPropagationDelay=0.000000E+000
|RECORD=2|OwnerIndex=482|OwnerPartId=1|FormalType=1|Electrical=7|PinConglomerate=56|PinLength=10|Location.X=910|Location.Y=720|Name=GND32|Designator=A23|SwapIDPart=Ž&Ž||PinPropagationDelay=0.000000E+000
|RECORD=2|OwnerIndex=482|OwnerPartId=1|FormalType=1|Electrical=7|PinConglomerate=56|PinLength=10|Location.X=910|Location.Y=710|Name=GND31|Designator=A24|SwapIDPart=Ž&Ž||PinPropagationDelay=0.000000E+000
|RECORD=2|OwnerIndex=482|OwnerPartId=1|FormalType=1|Electrical=4|PinConglomerate=56|PinLength=10|Location.X=910|Location.Y=700|Name=PERp2|Designator=A25|SwapIDPart=Ž&Ž||PinPropagationDelay=0.000000E+000
|RECORD=2|OwnerIndex=482|OwnerPartId=1|FormalType=1|Electrical=4|PinConglomerate=56|PinLength=10|Location.X=910|Location.Y=690|Name=PERn2|Designator=A26|SwapIDPart=Ž&Ž||PinPropagationDelay=0.000000E+000
|RECORD=2|OwnerIndex=482|OwnerPartId=1|FormalType=1|Electrical=7|PinConglomerate=56|PinLength=10|Location.X=910|Location.Y=680|Name=GND30|Designator=A27|SwapIDPart=Ž&Ž||PinPropagationDelay=0.000000E+000
|RECORD=2|OwnerIndex=482|OwnerPartId=1|FormalType=1|Electrical=7|PinConglomerate=56|PinLength=10|Location.X=910|Location.Y=670|Name=GND29|Designator=A28|SwapIDPart=Ž&Ž||PinPropagationDelay=0.000000E+000
|RECORD=2|OwnerIndex=482|OwnerPartId=1|FormalType=1|Electrical=4|PinConglomerate=56|PinLength=10|Location.X=910|Location.Y=660|Name=PERp3|Designator=A29|SwapIDPart=Ž&Ž||PinPropagationDelay=0.000000E+000
|RECORD=2|OwnerIndex=482|OwnerPartId=1|FormalType=1|Electrical=4|PinConglomerate=56|PinLength=10|Location.X=910|Location.Y=650|Name=PERn3|Designator=A30|SwapIDPart=Ž&Ž||PinPropagationDelay=0.000000E+000
|RECORD=2|OwnerIndex=482|OwnerPartId=1|FormalType=1|Electrical=7|PinConglomerate=56|PinLength=10|Location.X=910|Location.Y=640|Name=GND28|Designator=A31|SwapIDPart=Ž&Ž||PinPropagationDelay=0.000000E+000
|RECORD=2|OwnerIndex=482|OwnerPartId=1|FormalType=1|Electrical=4|PinConglomerate=56|PinLength=10|Location.X=910|Location.Y=630|Name=RESERVED4|Designator=A32|SwapIDPart=Ž&Ž||PinPropagationDelay=0.000000E+000
|RECORD=34|OwnerIndex=482|IndexInSheet=-1|OwnerPartId=1|Location.X=770|Location.Y=963|Color=8388608|FontID=8|Text=P2|Name=Designator|ReadOnlyState=1|OverrideNotAutoPosition=T
|RECORD=41|OwnerIndex=482|IndexInSheet=-1|OwnerPartId=-1|Location.X=882|Location.Y=609|Color=8388608|FontID=1|Text=PCIex4|Name=Comment|NotAutoPosition=T
|RECORD=44|OwnerIndex=482
|RECORD=45|OwnerIndex=621|IndexInSheet=-1|Description=PCIE_4LANE_EDGE|UseComponentLibrary=T|ModelName=PCIE_4LANE_EDGE|ModelType=PCBLIB|DatafileCount=1|ModelDatafileEntity0=PCIE_4LANE_EDGE|ModelDatafileKind0=PCBLib|IsCurrent=T|DatalinksLocked=T|DatabaseDatalinksLocked=T|IntegratedModel=T|DatabaseModel=T
|RECORD=46|OwnerIndex=622
|RECORD=48|OwnerIndex=622
|RECORD=45|OwnerIndex=621|IndexInSheet=-1|ModelName=ALINX_FPGA|ModelType=PCBLIB|DatafileCount=1|ModelDatafileEntity0=ALINX_FPGA|ModelDatafileKind0=PCBLib|IntegratedModel=T|DatabaseModel=T
|RECORD=46|OwnerIndex=625
|RECORD=48|OwnerIndex=625
|RECORD=17|IndexInSheet=47|OwnerPartId=-1|Style=4|ShowNetName=T|Location.X=1010|Location.Y=330|Orientation=3|Color=128|FontID=1|Text=GND
|RECORD=22|IndexInSheet=48|OwnerPartId=-1|Location.X=980|Location.Y=360|Color=255|Orientation=1|Symbol=Thin Cross|IsActive=T|SuppressAll=T
|RECORD=22|IndexInSheet=49|OwnerPartId=-1|Location.X=880|Location.Y=360|Color=255|Orientation=1|Symbol=Thin Cross|IsActive=T|SuppressAll=T
|RECORD=17|IndexInSheet=50|OwnerPartId=-1|ShowNetName=T|Location.X=1030|Location.Y=410|Orientation=1|Color=128|FontID=1|Text=+3.3V
|RECORD=17|IndexInSheet=51|OwnerPartId=-1|Style=4|ShowNetName=T|Location.X=590|Location.Y=180|Orientation=3|Color=128|FontID=1|Text=GND
|RECORD=17|IndexInSheet=52|OwnerPartId=-1|Style=4|ShowNetName=T|Location.X=730|Location.Y=180|Orientation=3|Color=128|FontID=1|Text=GND
|RECORD=17|IndexInSheet=53|OwnerPartId=-1|Style=4|ShowNetName=T|Location.X=870|Location.Y=180|Orientation=3|Color=128|FontID=1|Text=GND
|RECORD=17|IndexInSheet=54|OwnerPartId=-1|Style=4|ShowNetName=T|Location.X=1010|Location.Y=180|Orientation=3|Color=128|FontID=1|Text=GND
|RECORD=17|IndexInSheet=55|OwnerPartId=-1|ShowNetName=T|Location.X=630|Location.Y=170|Orientation=3|Color=128|FontID=1|Text=+3.3V
|RECORD=17|IndexInSheet=56|OwnerPartId=-1|ShowNetName=T|Location.X=770|Location.Y=169|Orientation=3|Color=128|FontID=1|Text=+3.3V
|RECORD=17|IndexInSheet=57|OwnerPartId=-1|ShowNetName=T|Location.X=910|Location.Y=170|Orientation=3|Color=128|FontID=1|Text=+3.3V
|RECORD=17|IndexInSheet=58|OwnerPartId=-1|ShowNetName=T|Location.X=1050|Location.Y=170|Orientation=3|Color=128|FontID=1|Text=+3.3V
|RECORD=17|IndexInSheet=59|OwnerPartId=-1|ShowNetName=T|Location.X=730|Location.Y=430|Orientation=2|Color=255|FontID=1|Text=FPGA_TCK|IsCrossSheetConnector=T
|RECORD=17|IndexInSheet=60|OwnerPartId=-1|ShowNetName=T|Location.X=730|Location.Y=400|Orientation=2|Color=255|FontID=1|Text=FPGA_TDO|IsCrossSheetConnector=T
|RECORD=17|IndexInSheet=61|OwnerPartId=-1|ShowNetName=T|Location.X=730|Location.Y=370|Orientation=2|Color=255|FontID=1|Text=FPGA_TMS|IsCrossSheetConnector=T
|RECORD=17|IndexInSheet=62|OwnerPartId=-1|ShowNetName=T|Location.X=730|Location.Y=340|Orientation=2|Color=255|FontID=1|Text=FPGA_TDI|IsCrossSheetConnector=T
|RECORD=4|IndexInSheet=63|OwnerPartId=-1|Location.X=910|Location.Y=430|Color=8388608|FontID=5|Text=JTAG
|RECORD=1|LibReference=RES_0805_33|ComponentDescription=RES, 33 OHM, 1%, 1/8W, TF, 0805|PartCount=2|DisplayModeCount=1|IndexInSheet=64|OwnerPartId=-1|Location.X=790|Location.Y=430|CurrentPartId=1|LibraryPath=*|SourceLibraryName=Resistors.IntLib|TargetFileName=*|AreaColor=11599871|Color=128|PartIDLocked=F|DesignItemId=RES_0805_33|AllPinCount=2
|RECORD=41|OwnerIndex=645|OwnerPartId=-1|Location.X=790|Location.Y=430|Color=8388608|FontID=7|IsHidden=T|Text=CRCW080533R0FKEA|Name=MFG PART NUM
|RECORD=41|OwnerIndex=645|IndexInSheet=1|OwnerPartId=-1|Location.X=790|Location.Y=430|Color=8388608|FontID=7|IsHidden=T|Text=VISHAY/DALE|Name=MFG NAME
|RECORD=41|OwnerIndex=645|IndexInSheet=2|OwnerPartId=-1|Location.X=790|Location.Y=430|Color=8388608|FontID=7|IsHidden=T|Text=RES|Name=CATEGORY
|RECORD=41|OwnerIndex=645|IndexInSheet=3|OwnerPartId=-1|Location.X=790|Location.Y=430|Color=8388608|FontID=7|IsHidden=T|Text=7/26/2013|Name=ModifyDate
|RECORD=41|OwnerIndex=645|IndexInSheet=4|OwnerPartId=-1|Location.X=788|Location.Y=440|Color=8388608|FontID=7|IsHidden=T|Name=Date
|RECORD=41|OwnerIndex=645|IndexInSheet=5|OwnerPartId=-1|Location.X=778|Location.X_Frac=55769|Location.Y=440|Color=8388608|FontID=7|IsHidden=T|Text=1%|Name=P1
|RECORD=41|OwnerIndex=645|IndexInSheet=6|OwnerPartId=-1|Location.X=778|Location.X_Frac=55769|Location.Y=440|Color=8388608|FontID=7|IsHidden=T|Text=TF|Name=P3
|RECORD=41|OwnerIndex=645|IndexInSheet=7|OwnerPartId=-1|Location.X=778|Location.X_Frac=55769|Location.Y=440|Color=8388608|FontID=7|IsHidden=T|Text=1/8W|Name=P2
|RECORD=41|OwnerIndex=645|IndexInSheet=8|OwnerPartId=-1|Location.X=778|Location.X_Frac=55769|Location.Y=440|Color=8388608|FontID=7|IsHidden=T|Text=125C|Name=MAXTEMP
|RECORD=41|OwnerIndex=645|IndexInSheet=9|OwnerPartId=-1|Location.X=778|Location.X_Frac=55769|Location.Y=440|Color=8388608|FontID=7|IsHidden=T|Text=-55C|Name=MINTEMP
|RECORD=41|OwnerIndex=645|IndexInSheet=10|OwnerPartId=-1|Location.X=778|Location.X_Frac=55769|Location.Y=440|Color=8388608|FontID=7|IsHidden=T|Text=100PPM|Name=OTHER
|RECORD=41|OwnerIndex=645|IndexInSheet=11|OwnerPartId=-1|Location.X=778|Location.X_Frac=55769|Location.Y=440|Color=8388608|FontID=7|IsHidden=T|Text=0805|Name=SIZE
|RECORD=41|OwnerIndex=645|IndexInSheet=12|OwnerPartId=-1|Location.X=778|Location.X_Frac=55769|Location.Y=440|Color=8388608|FontID=7|IsHidden=T|Name=SUB
|RECORD=41|OwnerIndex=645|IndexInSheet=13|OwnerPartId=-1|Location.X=778|Location.X_Frac=55769|Location.Y=440|Color=8388608|FontID=7|IsHidden=T|Text=Digi-Key|Name=Supplier 1|ReadOnlyState=3
|RECORD=41|OwnerIndex=645|IndexInSheet=14|OwnerPartId=-1|Location.X=778|Location.X_Frac=55769|Location.Y=440|Color=8388608|FontID=7|IsHidden=T|Text=541-33.0CCT-ND|Name=Supplier Part Number 1|ReadOnlyState=3
|RECORD=41|OwnerIndex=645|IndexInSheet=15|OwnerPartId=-1|Location.X=773|Location.X_Frac=98077|Location.Y=416|Color=8388608|FontID=1|IsHidden=T|Text=*|Name=SHEETPART
|RECORD=41|OwnerIndex=645|IndexInSheet=16|OwnerPartId=-1|Location.X=773|Location.X_Frac=98077|Location.Y=444|Color=8388608|FontID=1|IsHidden=T|Text=RES, 33 OHM, 1%, 1/8W, TF, 0805|Name=DESC
|RECORD=41|OwnerIndex=645|IndexInSheet=17|OwnerPartId=-1|Location.X=799|Location.Y=414|Color=8388608|FontID=7|Text=33 OHM|Name=VALUE
|RECORD=2|OwnerIndex=645|OwnerPartId=1|FormalType=1|Electrical=4|PinConglomerate=34|PinLength=10|Location.X=800|Location.Y=430|Name=1|Designator=1|PinPropagationDelay=0.000000E+000
|RECORD=2|OwnerIndex=645|OwnerPartId=1|FormalType=1|Electrical=4|PinConglomerate=32|PinLength=10|Location.X=830|Location.Y=430|Name=2|Designator=2|PinPropagationDelay=0.000000E+000
|RECORD=6|OwnerIndex=645|IsNotAccesible=T|IndexInSheet=20|OwnerPartId=1|LineWidth=1|Color=16711680|LocationCount=7|X1=830|Y1=430|X2=827|Y2=433|X3=821|Y3=427|X4=815|Y4=433|X5=809|Y5=427|X6=803|Y6=433|X7=800|Y7=430
|RECORD=41|OwnerIndex=645|IndexInSheet=21|OwnerPartId=-1|Location.X=774|Location.X_Frac=61102|Location.Y=444|Color=8388608|FontID=1|IsHidden=T|Text=<VELENTIUM>|Name=VELENTIUM PART NUM
|RECORD=34|OwnerIndex=645|IndexInSheet=-1|OwnerPartId=-1|Location.X=799|Location.Y=434|Color=8388608|FontID=1|Text=R18|Name=Designator|ReadOnlyState=1
|RECORD=41|OwnerIndex=645|IndexInSheet=-1|OwnerPartId=-1|Location.X=810|Location.Y=420|Color=8388608|FontID=1|IsHidden=T|Text==MFG PART NUM|Name=Comment
|RECORD=44|OwnerIndex=645
|RECORD=45|OwnerIndex=672|IndexInSheet=-1|Description=Chip Resistor, 0805, 2-Leads, Body 2.05x1.25mm, IPC Medium Density|UseComponentLibrary=T|ModelName=RESC2012X50N|ModelType=PCBLIB|DatafileCount=1|ModelDatafileEntity0=RESC2012X50N|ModelDatafileKind0=PCBLib|IsCurrent=T|DatalinksLocked=T|DatabaseDatalinksLocked=T|IntegratedModel=T|DatabaseModel=T
|RECORD=46|OwnerIndex=673
|RECORD=48|OwnerIndex=673
|RECORD=1|LibReference=RES_0805_33|ComponentDescription=RES, 33 OHM, 1%, 1/8W, TF, 0805|PartCount=2|DisplayModeCount=1|IndexInSheet=65|OwnerPartId=-1|Location.X=790|Location.Y=400|CurrentPartId=1|LibraryPath=*|SourceLibraryName=Resistors.IntLib|TargetFileName=*|AreaColor=11599871|Color=128|PartIDLocked=F|DesignItemId=RES_0805_33|AllPinCount=2
|RECORD=41|OwnerIndex=676|OwnerPartId=-1|Location.X=790|Location.Y=400|Color=8388608|FontID=7|IsHidden=T|Text=CRCW080533R0FKEA|Name=MFG PART NUM
|RECORD=41|OwnerIndex=676|IndexInSheet=1|OwnerPartId=-1|Location.X=790|Location.Y=400|Color=8388608|FontID=7|IsHidden=T|Text=VISHAY/DALE|Name=MFG NAME
|RECORD=41|OwnerIndex=676|IndexInSheet=2|OwnerPartId=-1|Location.X=790|Location.Y=400|Color=8388608|FontID=7|IsHidden=T|Text=RES|Name=CATEGORY
|RECORD=41|OwnerIndex=676|IndexInSheet=3|OwnerPartId=-1|Location.X=790|Location.Y=400|Color=8388608|FontID=7|IsHidden=T|Text=7/26/2013|Name=ModifyDate
|RECORD=41|OwnerIndex=676|IndexInSheet=4|OwnerPartId=-1|Location.X=788|Location.Y=410|Color=8388608|FontID=7|IsHidden=T|Name=Date
|RECORD=41|OwnerIndex=676|IndexInSheet=5|OwnerPartId=-1|Location.X=778|Location.X_Frac=55769|Location.Y=410|Color=8388608|FontID=7|IsHidden=T|Text=1%|Name=P1
|RECORD=41|OwnerIndex=676|IndexInSheet=6|OwnerPartId=-1|Location.X=778|Location.X_Frac=55769|Location.Y=410|Color=8388608|FontID=7|IsHidden=T|Text=TF|Name=P3
|RECORD=41|OwnerIndex=676|IndexInSheet=7|OwnerPartId=-1|Location.X=778|Location.X_Frac=55769|Location.Y=410|Color=8388608|FontID=7|IsHidden=T|Text=1/8W|Name=P2
|RECORD=41|OwnerIndex=676|IndexInSheet=8|OwnerPartId=-1|Location.X=778|Location.X_Frac=55769|Location.Y=410|Color=8388608|FontID=7|IsHidden=T|Text=125C|Name=MAXTEMP
|RECORD=41|OwnerIndex=676|IndexInSheet=9|OwnerPartId=-1|Location.X=778|Location.X_Frac=55769|Location.Y=410|Color=8388608|FontID=7|IsHidden=T|Text=-55C|Name=MINTEMP
|RECORD=41|OwnerIndex=676|IndexInSheet=10|OwnerPartId=-1|Location.X=778|Location.X_Frac=55769|Location.Y=410|Color=8388608|FontID=7|IsHidden=T|Text=100PPM|Name=OTHER
|RECORD=41|OwnerIndex=676|IndexInSheet=11|OwnerPartId=-1|Location.X=778|Location.X_Frac=55769|Location.Y=410|Color=8388608|FontID=7|IsHidden=T|Text=0805|Name=SIZE
|RECORD=41|OwnerIndex=676|IndexInSheet=12|OwnerPartId=-1|Location.X=778|Location.X_Frac=55769|Location.Y=410|Color=8388608|FontID=7|IsHidden=T|Name=SUB
|RECORD=41|OwnerIndex=676|IndexInSheet=13|OwnerPartId=-1|Location.X=778|Location.X_Frac=55769|Location.Y=410|Color=8388608|FontID=7|IsHidden=T|Text=Digi-Key|Name=Supplier 1|ReadOnlyState=3
|RECORD=41|OwnerIndex=676|IndexInSheet=14|OwnerPartId=-1|Location.X=778|Location.X_Frac=55769|Location.Y=410|Color=8388608|FontID=7|IsHidden=T|Text=541-33.0CCT-ND|Name=Supplier Part Number 1|ReadOnlyState=3
|RECORD=41|OwnerIndex=676|IndexInSheet=15|OwnerPartId=-1|Location.X=773|Location.X_Frac=98077|Location.Y=386|Color=8388608|FontID=1|IsHidden=T|Text=*|Name=SHEETPART
|RECORD=41|OwnerIndex=676|IndexInSheet=16|OwnerPartId=-1|Location.X=773|Location.X_Frac=98077|Location.Y=414|Color=8388608|FontID=1|IsHidden=T|Text=RES, 33 OHM, 1%, 1/8W, TF, 0805|Name=DESC
|RECORD=41|OwnerIndex=676|IndexInSheet=17|OwnerPartId=-1|Location.X=799|Location.Y=384|Color=8388608|FontID=7|Text=33 OHM|Name=VALUE
|RECORD=2|OwnerIndex=676|OwnerPartId=1|FormalType=1|Electrical=4|PinConglomerate=34|PinLength=10|Location.X=800|Location.Y=400|Name=1|Designator=1|PinPropagationDelay=0.000000E+000
|RECORD=2|OwnerIndex=676|OwnerPartId=1|FormalType=1|Electrical=4|PinConglomerate=32|PinLength=10|Location.X=830|Location.Y=400|Name=2|Designator=2|PinPropagationDelay=0.000000E+000
|RECORD=6|OwnerIndex=676|IsNotAccesible=T|IndexInSheet=20|OwnerPartId=1|LineWidth=1|Color=16711680|LocationCount=7|X1=830|Y1=400|X2=827|Y2=403|X3=821|Y3=397|X4=815|Y4=403|X5=809|Y5=397|X6=803|Y6=403|X7=800|Y7=400
|RECORD=41|OwnerIndex=676|IndexInSheet=21|OwnerPartId=-1|Location.X=774|Location.X_Frac=61102|Location.Y=414|Color=8388608|FontID=1|IsHidden=T|Text=<VELENTIUM>|Name=VELENTIUM PART NUM
|RECORD=34|OwnerIndex=676|IndexInSheet=-1|OwnerPartId=-1|Location.X=799|Location.Y=404|Color=8388608|FontID=1|Text=R19|Name=Designator|ReadOnlyState=1
|RECORD=41|OwnerIndex=676|IndexInSheet=-1|OwnerPartId=-1|Location.X=810|Location.Y=390|Color=8388608|FontID=1|IsHidden=T|Text==MFG PART NUM|Name=Comment
|RECORD=44|OwnerIndex=676
|RECORD=45|OwnerIndex=703|IndexInSheet=-1|Description=Chip Resistor, 0805, 2-Leads, Body 2.05x1.25mm, IPC Medium Density|UseComponentLibrary=T|ModelName=RESC2012X50N|ModelType=PCBLIB|DatafileCount=1|ModelDatafileEntity0=RESC2012X50N|ModelDatafileKind0=PCBLib|IsCurrent=T|DatalinksLocked=T|DatabaseDatalinksLocked=T|IntegratedModel=T|DatabaseModel=T
|RECORD=46|OwnerIndex=704
|RECORD=48|OwnerIndex=704
|RECORD=1|LibReference=RES_0805_33|ComponentDescription=RES, 33 OHM, 1%, 1/8W, TF, 0805|PartCount=2|DisplayModeCount=1|IndexInSheet=66|OwnerPartId=-1|Location.X=790|Location.Y=370|CurrentPartId=1|LibraryPath=*|SourceLibraryName=Resistors.IntLib|TargetFileName=*|AreaColor=11599871|Color=128|PartIDLocked=F|DesignItemId=RES_0805_33|AllPinCount=2
|RECORD=41|OwnerIndex=707|OwnerPartId=-1|Location.X=790|Location.Y=370|Color=8388608|FontID=7|IsHidden=T|Text=CRCW080533R0FKEA|Name=MFG PART NUM
|RECORD=41|OwnerIndex=707|IndexInSheet=1|OwnerPartId=-1|Location.X=790|Location.Y=370|Color=8388608|FontID=7|IsHidden=T|Text=VISHAY/DALE|Name=MFG NAME
|RECORD=41|OwnerIndex=707|IndexInSheet=2|OwnerPartId=-1|Location.X=790|Location.Y=370|Color=8388608|FontID=7|IsHidden=T|Text=RES|Name=CATEGORY
|RECORD=41|OwnerIndex=707|IndexInSheet=3|OwnerPartId=-1|Location.X=790|Location.Y=370|Color=8388608|FontID=7|IsHidden=T|Text=7/26/2013|Name=ModifyDate
|RECORD=41|OwnerIndex=707|IndexInSheet=4|OwnerPartId=-1|Location.X=788|Location.Y=380|Color=8388608|FontID=7|IsHidden=T|Name=Date
|RECORD=41|OwnerIndex=707|IndexInSheet=5|OwnerPartId=-1|Location.X=778|Location.X_Frac=55769|Location.Y=380|Color=8388608|FontID=7|IsHidden=T|Text=1%|Name=P1
|RECORD=41|OwnerIndex=707|IndexInSheet=6|OwnerPartId=-1|Location.X=778|Location.X_Frac=55769|Location.Y=380|Color=8388608|FontID=7|IsHidden=T|Text=TF|Name=P3
|RECORD=41|OwnerIndex=707|IndexInSheet=7|OwnerPartId=-1|Location.X=778|Location.X_Frac=55769|Location.Y=380|Color=8388608|FontID=7|IsHidden=T|Text=1/8W|Name=P2
|RECORD=41|OwnerIndex=707|IndexInSheet=8|OwnerPartId=-1|Location.X=778|Location.X_Frac=55769|Location.Y=380|Color=8388608|FontID=7|IsHidden=T|Text=125C|Name=MAXTEMP
|RECORD=41|OwnerIndex=707|IndexInSheet=9|OwnerPartId=-1|Location.X=778|Location.X_Frac=55769|Location.Y=380|Color=8388608|FontID=7|IsHidden=T|Text=-55C|Name=MINTEMP
|RECORD=41|OwnerIndex=707|IndexInSheet=10|OwnerPartId=-1|Location.X=778|Location.X_Frac=55769|Location.Y=380|Color=8388608|FontID=7|IsHidden=T|Text=100PPM|Name=OTHER
|RECORD=41|OwnerIndex=707|IndexInSheet=11|OwnerPartId=-1|Location.X=778|Location.X_Frac=55769|Location.Y=380|Color=8388608|FontID=7|IsHidden=T|Text=0805|Name=SIZE
|RECORD=41|OwnerIndex=707|IndexInSheet=12|OwnerPartId=-1|Location.X=778|Location.X_Frac=55769|Location.Y=380|Color=8388608|FontID=7|IsHidden=T|Name=SUB
|RECORD=41|OwnerIndex=707|IndexInSheet=13|OwnerPartId=-1|Location.X=778|Location.X_Frac=55769|Location.Y=380|Color=8388608|FontID=7|IsHidden=T|Text=Digi-Key|Name=Supplier 1|ReadOnlyState=3
|RECORD=41|OwnerIndex=707|IndexInSheet=14|OwnerPartId=-1|Location.X=778|Location.X_Frac=55769|Location.Y=380|Color=8388608|FontID=7|IsHidden=T|Text=541-33.0CCT-ND|Name=Supplier Part Number 1|ReadOnlyState=3
|RECORD=41|OwnerIndex=707|IndexInSheet=15|OwnerPartId=-1|Location.X=773|Location.X_Frac=98077|Location.Y=356|Color=8388608|FontID=1|IsHidden=T|Text=*|Name=SHEETPART
|RECORD=41|OwnerIndex=707|IndexInSheet=16|OwnerPartId=-1|Location.X=773|Location.X_Frac=98077|Location.Y=384|Color=8388608|FontID=1|IsHidden=T|Text=RES, 33 OHM, 1%, 1/8W, TF, 0805|Name=DESC
|RECORD=41|OwnerIndex=707|IndexInSheet=17|OwnerPartId=-1|Location.X=799|Location.Y=354|Color=8388608|FontID=7|Text=33 OHM|Name=VALUE
|RECORD=2|OwnerIndex=707|OwnerPartId=1|FormalType=1|Electrical=4|PinConglomerate=34|PinLength=10|Location.X=800|Location.Y=370|Name=1|Designator=1|PinPropagationDelay=0.000000E+000
|RECORD=2|OwnerIndex=707|OwnerPartId=1|FormalType=1|Electrical=4|PinConglomerate=32|PinLength=10|Location.X=830|Location.Y=370|Name=2|Designator=2|PinPropagationDelay=0.000000E+000
|RECORD=6|OwnerIndex=707|IsNotAccesible=T|IndexInSheet=20|OwnerPartId=1|LineWidth=1|Color=16711680|LocationCount=7|X1=830|Y1=370|X2=827|Y2=373|X3=821|Y3=367|X4=815|Y4=373|X5=809|Y5=367|X6=803|Y6=373|X7=800|Y7=370
|RECORD=41|OwnerIndex=707|IndexInSheet=21|OwnerPartId=-1|Location.X=774|Location.X_Frac=61102|Location.Y=384|Color=8388608|FontID=1|IsHidden=T|Text=<VELENTIUM>|Name=VELENTIUM PART NUM
|RECORD=34|OwnerIndex=707|IndexInSheet=-1|OwnerPartId=-1|Location.X=799|Location.Y=374|Color=8388608|FontID=1|Text=R20|Name=Designator|ReadOnlyState=1
|RECORD=41|OwnerIndex=707|IndexInSheet=-1|OwnerPartId=-1|Location.X=810|Location.Y=360|Color=8388608|FontID=1|IsHidden=T|Text==MFG PART NUM|Name=Comment
|RECORD=44|OwnerIndex=707
|RECORD=45|OwnerIndex=734|IndexInSheet=-1|Description=Chip Resistor, 0805, 2-Leads, Body 2.05x1.25mm, IPC Medium Density|UseComponentLibrary=T|ModelName=RESC2012X50N|ModelType=PCBLIB|DatafileCount=1|ModelDatafileEntity0=RESC2012X50N|ModelDatafileKind0=PCBLib|IsCurrent=T|DatalinksLocked=T|DatabaseDatalinksLocked=T|IntegratedModel=T|DatabaseModel=T
|RECORD=46|OwnerIndex=735
|RECORD=48|OwnerIndex=735
|RECORD=1|LibReference=RES_0805_33|ComponentDescription=RES, 33 OHM, 1%, 1/8W, TF, 0805|PartCount=2|DisplayModeCount=1|IndexInSheet=67|OwnerPartId=-1|Location.X=790|Location.Y=340|CurrentPartId=1|LibraryPath=*|SourceLibraryName=Resistors.IntLib|TargetFileName=*|AreaColor=11599871|Color=128|PartIDLocked=F|DesignItemId=RES_0805_33|AllPinCount=2
|RECORD=41|OwnerIndex=738|OwnerPartId=-1|Location.X=790|Location.Y=340|Color=8388608|FontID=7|IsHidden=T|Text=CRCW080533R0FKEA|Name=MFG PART NUM
|RECORD=41|OwnerIndex=738|IndexInSheet=1|OwnerPartId=-1|Location.X=790|Location.Y=340|Color=8388608|FontID=7|IsHidden=T|Text=VISHAY/DALE|Name=MFG NAME
|RECORD=41|OwnerIndex=738|IndexInSheet=2|OwnerPartId=-1|Location.X=790|Location.Y=340|Color=8388608|FontID=7|IsHidden=T|Text=RES|Name=CATEGORY
|RECORD=41|OwnerIndex=738|IndexInSheet=3|OwnerPartId=-1|Location.X=790|Location.Y=340|Color=8388608|FontID=7|IsHidden=T|Text=7/26/2013|Name=ModifyDate
|RECORD=41|OwnerIndex=738|IndexInSheet=4|OwnerPartId=-1|Location.X=788|Location.Y=350|Color=8388608|FontID=7|IsHidden=T|Name=Date
|RECORD=41|OwnerIndex=738|IndexInSheet=5|OwnerPartId=-1|Location.X=778|Location.X_Frac=55769|Location.Y=350|Color=8388608|FontID=7|IsHidden=T|Text=1%|Name=P1
|RECORD=41|OwnerIndex=738|IndexInSheet=6|OwnerPartId=-1|Location.X=778|Location.X_Frac=55769|Location.Y=350|Color=8388608|FontID=7|IsHidden=T|Text=TF|Name=P3
|RECORD=41|OwnerIndex=738|IndexInSheet=7|OwnerPartId=-1|Location.X=778|Location.X_Frac=55769|Location.Y=350|Color=8388608|FontID=7|IsHidden=T|Text=1/8W|Name=P2
|RECORD=41|OwnerIndex=738|IndexInSheet=8|OwnerPartId=-1|Location.X=778|Location.X_Frac=55769|Location.Y=350|Color=8388608|FontID=7|IsHidden=T|Text=125C|Name=MAXTEMP
|RECORD=41|OwnerIndex=738|IndexInSheet=9|OwnerPartId=-1|Location.X=778|Location.X_Frac=55769|Location.Y=350|Color=8388608|FontID=7|IsHidden=T|Text=-55C|Name=MINTEMP
|RECORD=41|OwnerIndex=738|IndexInSheet=10|OwnerPartId=-1|Location.X=778|Location.X_Frac=55769|Location.Y=350|Color=8388608|FontID=7|IsHidden=T|Text=100PPM|Name=OTHER
|RECORD=41|OwnerIndex=738|IndexInSheet=11|OwnerPartId=-1|Location.X=778|Location.X_Frac=55769|Location.Y=350|Color=8388608|FontID=7|IsHidden=T|Text=0805|Name=SIZE
|RECORD=41|OwnerIndex=738|IndexInSheet=12|OwnerPartId=-1|Location.X=778|Location.X_Frac=55769|Location.Y=350|Color=8388608|FontID=7|IsHidden=T|Name=SUB
|RECORD=41|OwnerIndex=738|IndexInSheet=13|OwnerPartId=-1|Location.X=778|Location.X_Frac=55769|Location.Y=350|Color=8388608|FontID=7|IsHidden=T|Text=Digi-Key|Name=Supplier 1|ReadOnlyState=3
|RECORD=41|OwnerIndex=738|IndexInSheet=14|OwnerPartId=-1|Location.X=778|Location.X_Frac=55769|Location.Y=350|Color=8388608|FontID=7|IsHidden=T|Text=541-33.0CCT-ND|Name=Supplier Part Number 1|ReadOnlyState=3
|RECORD=41|OwnerIndex=738|IndexInSheet=15|OwnerPartId=-1|Location.X=773|Location.X_Frac=98077|Location.Y=326|Color=8388608|FontID=1|IsHidden=T|Text=*|Name=SHEETPART
|RECORD=41|OwnerIndex=738|IndexInSheet=16|OwnerPartId=-1|Location.X=773|Location.X_Frac=98077|Location.Y=354|Color=8388608|FontID=1|IsHidden=T|Text=RES, 33 OHM, 1%, 1/8W, TF, 0805|Name=DESC
|RECORD=41|OwnerIndex=738|IndexInSheet=17|OwnerPartId=-1|Location.X=799|Location.Y=324|Color=8388608|FontID=7|Text=33 OHM|Name=VALUE
|RECORD=2|OwnerIndex=738|OwnerPartId=1|FormalType=1|Electrical=4|PinConglomerate=34|PinLength=10|Location.X=800|Location.Y=340|Name=1|Designator=1|PinPropagationDelay=0.000000E+000
|RECORD=2|OwnerIndex=738|OwnerPartId=1|FormalType=1|Electrical=4|PinConglomerate=32|PinLength=10|Location.X=830|Location.Y=340|Name=2|Designator=2|PinPropagationDelay=0.000000E+000
|RECORD=6|OwnerIndex=738|IsNotAccesible=T|IndexInSheet=20|OwnerPartId=1|LineWidth=1|Color=16711680|LocationCount=7|X1=830|Y1=340|X2=827|Y2=343|X3=821|Y3=337|X4=815|Y4=343|X5=809|Y5=337|X6=803|Y6=343|X7=800|Y7=340
|RECORD=41|OwnerIndex=738|IndexInSheet=21|OwnerPartId=-1|Location.X=774|Location.X_Frac=61102|Location.Y=354|Color=8388608|FontID=1|IsHidden=T|Text=<VELENTIUM>|Name=VELENTIUM PART NUM
|RECORD=34|OwnerIndex=738|IndexInSheet=-1|OwnerPartId=-1|Location.X=799|Location.Y=344|Color=8388608|FontID=1|Text=R21|Name=Designator|ReadOnlyState=1
|RECORD=41|OwnerIndex=738|IndexInSheet=-1|OwnerPartId=-1|Location.X=810|Location.Y=330|Color=8388608|FontID=1|IsHidden=T|Text==MFG PART NUM|Name=Comment
|RECORD=44|OwnerIndex=738
|RECORD=45|OwnerIndex=765|IndexInSheet=-1|Description=Chip Resistor, 0805, 2-Leads, Body 2.05x1.25mm, IPC Medium Density|UseComponentLibrary=T|ModelName=RESC2012X50N|ModelType=PCBLIB|DatafileCount=1|ModelDatafileEntity0=RESC2012X50N|ModelDatafileKind0=PCBLib|IsCurrent=T|DatalinksLocked=T|DatabaseDatalinksLocked=T|IntegratedModel=T|DatabaseModel=T
|RECORD=46|OwnerIndex=766
|RECORD=48|OwnerIndex=766
|RECORD=1|LibReference=SAMTEC-HTSH-105-01-L-DV|ComponentDescription=CONN, HDR, 2X5, VERT, 0.1IN  SHROUDED, SMT, HTSH SERIES|PartCount=2|DisplayModeCount=1|IndexInSheet=68|OwnerPartId=-1|Location.X=870|Location.Y=390|CurrentPartId=1|LibraryPath=*|SourceLibraryName=Connectors.IntLib|TargetFileName=*|AreaColor=11599871|Color=128|PartIDLocked=F|DesignItemId=SAMTEC-HTSH-105-01-L-DV|AllPinCount=10
|RECORD=41|OwnerIndex=769|OwnerPartId=-1|Location.X=870|Location.Y=390|Color=8388608|FontID=7|IsHidden=T|Text=HTST-105-01-L-DV-A|Name=MFG PART NUM
|RECORD=41|OwnerIndex=769|IndexInSheet=1|OwnerPartId=-1|Location.X=870|Location.Y=390|Color=8388608|FontID=7|IsHidden=T|Text=10/10/2013|Name=MODIFY DATE
|RECORD=41|OwnerIndex=769|IndexInSheet=2|OwnerPartId=-1|Location.X=870|Location.Y=390|Color=8388608|FontID=7|IsHidden=T|Text=SAMTEC INC|Name=MFG NAME
|RECORD=41|OwnerIndex=769|IndexInSheet=3|OwnerPartId=-1|Location.X=868|Location.Y=415|Color=8388608|FontID=7|IsHidden=T|Text=CONN, HDR|Name=CATEGORY
|RECORD=41|OwnerIndex=769|IndexInSheet=4|OwnerPartId=-1|Location.X=868|Location.Y=415|Color=8388608|FontID=7|IsHidden=T|Text=125C|Name=MAXTEMP
|RECORD=41|OwnerIndex=769|IndexInSheet=5|OwnerPartId=-1|Location.X=868|Location.Y=415|Color=8388608|FontID=7|IsHidden=T|Text=-55C|Name=MINTEMP
|RECORD=41|OwnerIndex=769|IndexInSheet=6|OwnerPartId=-1|Location.X=868|Location.Y=415|Color=8388608|FontID=7|IsHidden=T|Text=HTSH SERIES|Name=OTHER
|RECORD=41|OwnerIndex=769|IndexInSheet=7|OwnerPartId=-1|Location.X=868|Location.Y=415|Color=8388608|FontID=7|IsHidden=T|Text=VERT|Name=P1
|RECORD=41|OwnerIndex=769|IndexInSheet=8|OwnerPartId=-1|Location.X=868|Location.Y=415|Color=8388608|FontID=7|IsHidden=T|Text=0.1 IN|Name=P2
|RECORD=41|OwnerIndex=769|IndexInSheet=9|OwnerPartId=-1|Location.X=868|Location.Y=415|Color=8388608|FontID=7|IsHidden=T|Text=SHROUDED|Name=P3
|RECORD=41|OwnerIndex=769|IndexInSheet=10|OwnerPartId=-1|Location.X=868|Location.Y=415|Color=8388608|FontID=7|IsHidden=T|Text=SMT|Name=SIZE
|RECORD=41|OwnerIndex=769|IndexInSheet=11|OwnerPartId=-1|Location.X=868|Location.Y=415|Color=8388608|FontID=7|IsHidden=T|Name=SUB
|RECORD=41|OwnerIndex=769|IndexInSheet=12|OwnerPartId=-1|Location.X=868|Location.Y=309|Color=8388608|FontID=7|IsHidden=T|Name=SHEETPART
|RECORD=41|OwnerIndex=769|IndexInSheet=13|OwnerPartId=-1|Location.X=868|Location.Y=309|Color=8388608|FontID=7|IsHidden=T|Name=DATE
|RECORD=41|OwnerIndex=769|IndexInSheet=14|OwnerPartId=-1|Location.X=868|Location.Y=419|Color=8388608|FontID=1|IsHidden=T|Text=CONN, HDR, 2X5, VERT, 0.1IN  SHROUDED, SMT, HTSH SERIES|Name=DESC
|RECORD=41|OwnerIndex=769|IndexInSheet=15|OwnerPartId=-1|Location.X=868|Location.Y=419|Color=8388608|FontID=1|IsHidden=T|Text=<VALENTIUM>|Name=VALENTIUM PART NUM
|RECORD=41|OwnerIndex=769|IndexInSheet=16|OwnerPartId=-1|Location.X=860|Location.Y=422|Color=8388608|FontID=1|IsHidden=T|Text=Digi-Key|Name=Supplier 1|ReadOnlyState=3
|RECORD=41|OwnerIndex=769|IndexInSheet=17|OwnerPartId=-1|Location.X=860|Location.Y=422|Color=8388608|FontID=1|IsHidden=T|Text=SAM8809-ND|Name=Supplier Part Number 1|ReadOnlyState=3
|RECORD=41|OwnerIndex=769|IndexInSheet=18|OwnerPartId=-1|Location.X=908|Location.X_Frac=50000|Location.Y=328|Color=8388608|FontID=7|Text=2X5|Name=VALUE
|RECORD=2|OwnerIndex=769|OwnerPartId=1|FormalType=1|Electrical=4|PinConglomerate=50|PinLength=30|Location.X=910|Location.Y=350|Name=P9|Designator=9|PinPropagationDelay=0.000000E+000
|RECORD=2|OwnerIndex=769|OwnerPartId=1|FormalType=1|Electrical=4|PinConglomerate=50|PinLength=30|Location.X=910|Location.Y=380|Name=P3|Designator=3|PinPropagationDelay=0.000000E+000
|RECORD=2|OwnerIndex=769|OwnerPartId=1|FormalType=1|Electrical=4|PinConglomerate=48|PinLength=30|Location.X=950|Location.Y=350|Name=P10|Designator=10|PinPropagationDelay=0.000000E+000
|RECORD=2|OwnerIndex=769|OwnerPartId=1|FormalType=1|Electrical=4|PinConglomerate=48|PinLength=30|Location.X=950|Location.Y=380|Name=P4|Designator=4|PinPropagationDelay=0.000000E+000
|RECORD=2|OwnerIndex=769|OwnerPartId=1|FormalType=1|Electrical=4|PinConglomerate=50|PinLength=30|Location.X=910|Location.Y=390|Name=P1|Designator=1|PinPropagationDelay=0.000000E+000
|RECORD=2|OwnerIndex=769|OwnerPartId=1|FormalType=1|Electrical=4|PinConglomerate=50|PinLength=30|Location.X=910|Location.Y=370|Name=P5|Designator=5|PinPropagationDelay=0.000000E+000
|RECORD=2|OwnerIndex=769|OwnerPartId=1|FormalType=1|Electrical=4|PinConglomerate=50|PinLength=30|Location.X=910|Location.Y=360|Name=P7|Designator=7|PinPropagationDelay=0.000000E+000
|RECORD=2|OwnerIndex=769|OwnerPartId=1|FormalType=1|Electrical=4|PinConglomerate=48|PinLength=30|Location.X=950|Location.Y=390|Name=P2|Designator=2|PinPropagationDelay=0.000000E+000
|RECORD=2|OwnerIndex=769|OwnerPartId=1|FormalType=1|Electrical=4|PinConglomerate=48|PinLength=30|Location.X=950|Location.Y=370|Name=P6|Designator=6|PinPropagationDelay=0.000000E+000
|RECORD=2|OwnerIndex=769|OwnerPartId=1|FormalType=1|Electrical=4|PinConglomerate=48|PinLength=30|Location.X=950|Location.Y=360|Name=P8|Designator=8|PinPropagationDelay=0.000000E+000
|RECORD=13|OwnerIndex=769|IsNotAccesible=T|IndexInSheet=29|OwnerPartId=1|Location.X=917|Location.X_Frac=50000|Location.Y=365|Corner.X=922|Corner.X_Frac=50000|Corner.Y=360|LineWidth=1|Color=16711680
|RECORD=13|OwnerIndex=769|IsNotAccesible=T|IndexInSheet=30|OwnerPartId=1|Location.X=917|Location.X_Frac=50000|Location.Y=355|Corner.X=922|Corner.X_Frac=50000|Corner.Y=360|LineWidth=1|Color=16711680
|RECORD=13|OwnerIndex=769|IsNotAccesible=T|IndexInSheet=31|OwnerPartId=1|Location.X=917|Location.X_Frac=50000|Location.Y=355|Corner.X=922|Corner.X_Frac=50000|Corner.Y=350|LineWidth=1|Color=16711680
|RECORD=13|OwnerIndex=769|IsNotAccesible=T|IndexInSheet=32|OwnerPartId=1|Location.X=917|Location.X_Frac=50000|Location.Y=345|Corner.X=922|Corner.X_Frac=50000|Corner.Y=350|LineWidth=1|Color=16711680
|RECORD=13|OwnerIndex=769|IsNotAccesible=T|IndexInSheet=33|OwnerPartId=1|Location.X=917|Location.X_Frac=50000|Location.Y=395|Corner.X=922|Corner.X_Frac=50000|Corner.Y=390|LineWidth=1|Color=16711680
|RECORD=13|OwnerIndex=769|IsNotAccesible=T|IndexInSheet=34|OwnerPartId=1|Location.X=917|Location.X_Frac=50000|Location.Y=385|Corner.X=922|Corner.X_Frac=50000|Corner.Y=390|LineWidth=1|Color=16711680
|RECORD=13|OwnerIndex=769|IsNotAccesible=T|IndexInSheet=35|OwnerPartId=1|Location.X=917|Location.X_Frac=50000|Location.Y=385|Corner.X=922|Corner.X_Frac=50000|Corner.Y=380|LineWidth=1|Color=16711680
|RECORD=13|OwnerIndex=769|IsNotAccesible=T|IndexInSheet=36|OwnerPartId=1|Location.X=917|Location.X_Frac=50000|Location.Y=375|Corner.X=922|Corner.X_Frac=50000|Corner.Y=380|LineWidth=1|Color=16711680
|RECORD=13|OwnerIndex=769|IsNotAccesible=T|IndexInSheet=37|OwnerPartId=1|Location.X=942|Location.X_Frac=50000|Location.Y=355|Corner.X=937|Corner.X_Frac=50000|Corner.Y=350|LineWidth=1|Color=16711680
|RECORD=13|OwnerIndex=769|IsNotAccesible=T|IndexInSheet=38|OwnerPartId=1|Location.X=942|Location.X_Frac=50000|Location.Y=355|Corner.X=937|Corner.X_Frac=50000|Corner.Y=360|LineWidth=1|Color=16711680
|RECORD=13|OwnerIndex=769|IsNotAccesible=T|IndexInSheet=39|OwnerPartId=1|Location.X=942|Location.X_Frac=50000|Location.Y=365|Corner.X=937|Corner.X_Frac=50000|Corner.Y=360|LineWidth=1|Color=16711680
|RECORD=13|OwnerIndex=769|IsNotAccesible=T|IndexInSheet=40|OwnerPartId=1|Location.X=942|Location.X_Frac=50000|Location.Y=345|Corner.X=937|Corner.X_Frac=50000|Corner.Y=350|LineWidth=1|Color=16711680
|RECORD=13|OwnerIndex=769|IsNotAccesible=T|IndexInSheet=41|OwnerPartId=1|Location.X=942|Location.X_Frac=50000|Location.Y=375|Corner.X=937|Corner.X_Frac=50000|Corner.Y=380|LineWidth=1|Color=16711680
|RECORD=13|OwnerIndex=769|IsNotAccesible=T|IndexInSheet=42|OwnerPartId=1|Location.X=942|Location.X_Frac=50000|Location.Y=385|Corner.X=937|Corner.X_Frac=50000|Corner.Y=380|LineWidth=1|Color=16711680
|RECORD=13|OwnerIndex=769|IsNotAccesible=T|IndexInSheet=43|OwnerPartId=1|Location.X=942|Location.X_Frac=50000|Location.Y=385|Corner.X=937|Corner.X_Frac=50000|Corner.Y=390|LineWidth=1|Color=16711680
|RECORD=13|OwnerIndex=769|IsNotAccesible=T|IndexInSheet=44|OwnerPartId=1|Location.X=942|Location.X_Frac=50000|Location.Y=395|Corner.X=937|Corner.X_Frac=50000|Corner.Y=390|LineWidth=1|Color=16711680
|RECORD=13|OwnerIndex=769|IsNotAccesible=T|IndexInSheet=45|OwnerPartId=1|Location.X=917|Location.X_Frac=50000|Location.Y=375|Corner.X=922|Corner.X_Frac=50000|Corner.Y=370|LineWidth=1|Color=16711680
|RECORD=13|OwnerIndex=769|IsNotAccesible=T|IndexInSheet=46|OwnerPartId=1|Location.X=917|Location.X_Frac=50000|Location.Y=365|Corner.X=922|Corner.X_Frac=50000|Corner.Y=370|LineWidth=1|Color=16711680
|RECORD=13|OwnerIndex=769|IsNotAccesible=T|IndexInSheet=47|OwnerPartId=1|Location.X=942|Location.X_Frac=50000|Location.Y=365|Corner.X=937|Corner.X_Frac=50000|Corner.Y=370|LineWidth=1|Color=16711680
|RECORD=13|OwnerIndex=769|IsNotAccesible=T|IndexInSheet=48|OwnerPartId=1|Location.X=942|Location.X_Frac=50000|Location.Y=375|Corner.X=937|Corner.X_Frac=50000|Corner.Y=370|LineWidth=1|Color=16711680
|RECORD=13|OwnerIndex=769|IsNotAccesible=T|IndexInSheet=49|OwnerPartId=1|Location.X=950|Location.Y=350|Corner.X=937|Corner.X_Frac=50000|Corner.Y=350|LineWidth=1|Color=16711680
|RECORD=13|OwnerIndex=769|IsNotAccesible=T|IndexInSheet=50|OwnerPartId=1|Location.X=950|Location.Y=360|Corner.X=937|Corner.X_Frac=50000|Corner.Y=360|LineWidth=1|Color=16711680
|RECORD=13|OwnerIndex=769|IsNotAccesible=T|IndexInSheet=51|OwnerPartId=1|Location.X=950|Location.Y=370|Corner.X=937|Corner.X_Frac=50000|Corner.Y=370|LineWidth=1|Color=16711680
|RECORD=13|OwnerIndex=769|IsNotAccesible=T|IndexInSheet=52|OwnerPartId=1|Location.X=950|Location.Y=380|Corner.X=937|Corner.X_Frac=50000|Corner.Y=380|LineWidth=1|Color=16711680
|RECORD=13|OwnerIndex=769|IsNotAccesible=T|IndexInSheet=53|OwnerPartId=1|Location.X=950|Location.Y=390|Corner.X=937|Corner.X_Frac=50000|Corner.Y=390|LineWidth=1|Color=16711680
|RECORD=13|OwnerIndex=769|IsNotAccesible=T|IndexInSheet=54|OwnerPartId=1|Location.X=922|Location.Y=390|Corner.X=909|Corner.X_Frac=50000|Corner.Y=390|LineWidth=1|Color=16711680
|RECORD=13|OwnerIndex=769|IsNotAccesible=T|IndexInSheet=55|OwnerPartId=1|Location.X=922|Location.Y=380|Corner.X=909|Corner.X_Frac=50000|Corner.Y=380|LineWidth=1|Color=16711680
|RECORD=13|OwnerIndex=769|IsNotAccesible=T|IndexInSheet=56|OwnerPartId=1|Location.X=922|Location.Y=370|Corner.X=909|Corner.X_Frac=50000|Corner.Y=370|LineWidth=1|Color=16711680
|RECORD=13|OwnerIndex=769|IsNotAccesible=T|IndexInSheet=57|OwnerPartId=1|Location.X=922|Location.Y=360|Corner.X=909|Corner.X_Frac=50000|Corner.Y=360|LineWidth=1|Color=16711680
|RECORD=13|OwnerIndex=769|IsNotAccesible=T|IndexInSheet=58|OwnerPartId=1|Location.X=922|Location.Y=350|Corner.X=909|Corner.X_Frac=50000|Corner.Y=350|LineWidth=1|Color=16711680
|RECORD=14|OwnerIndex=769|IsNotAccesible=T|IndexInSheet=59|OwnerPartId=1|Location.X=910|Location.Y=340|Corner.X=950|Corner.Y=400|Color=128|AreaColor=11599871|IsSolid=T|Transparent=T
|RECORD=34|OwnerIndex=769|IndexInSheet=-1|OwnerPartId=-1|Location.X=908|Location.X_Frac=50000|Location.Y=400|Color=8388608|FontID=1|Text=U5|Name=Designator|ReadOnlyState=1
|RECORD=41|OwnerIndex=769|IndexInSheet=-1|OwnerPartId=-1|Location.X=910|Location.Y=310|Color=8388608|FontID=1|IsHidden=T|Text==MFG PART NUM|Name=Comment
|RECORD=44|OwnerIndex=769
|RECORD=45|OwnerIndex=842|IndexInSheet=-1|UseComponentLibrary=T|ModelName=SAMTEC_HTST-105-01-L-DV-A|ModelType=PCBLIB|DatafileCount=1|ModelDatafileEntity0=SAMTEC_HTST-105-01-L-DV-A|ModelDatafileKind0=PCBLib|IsCurrent=T|DatalinksLocked=T|DatabaseDatalinksLocked=T|IntegratedModel=T|DatabaseModel=T
|RECORD=46|OwnerIndex=843
|RECORD=48|OwnerIndex=843
|RECORD=1|LibReference=BAT54SW|ComponentDescription=DIO, SCHOTTKY, BAT54S, DUAL SERIES, 30V, 200MA, SC-70|PartCount=2|DisplayModeCount=1|IndexInSheet=69|OwnerPartId=-1|Location.X=1020|Location.Y=180|Orientation=1|CurrentPartId=1|LibraryPath=*|SourceLibraryName=Passives.IntLib|TargetFileName=*|AreaColor=11599871|Color=128|PartIDLocked=F|DesignItemId=BAT54SW|AllPinCount=3
|RECORD=41|OwnerIndex=846|OwnerPartId=-1|Location.X=1009|Location.Y=252|Color=8388608|FontID=7|IsHidden=T|Text=BAT54SWQ-7-F|Name=MFG PART NUM
|RECORD=41|OwnerIndex=846|IndexInSheet=1|OwnerPartId=-1|Location.X=1009|Location.Y=252|Color=8388608|FontID=7|IsHidden=T|Text=9/4/2013|Name=MODIFY DATE
|RECORD=41|OwnerIndex=846|IndexInSheet=2|OwnerPartId=-1|Location.X=1009|Location.Y=252|Color=8388608|FontID=7|IsHidden=T|Text=DIODES INC|Name=MFG NAME
|RECORD=41|OwnerIndex=846|IndexInSheet=3|OwnerPartId=-1|Location.X=1009|Location.Y=252|Color=8388608|FontID=7|IsHidden=T|Text=DIO, SCHOTTKY|Name=CATEGORY
|RECORD=41|OwnerIndex=846|IndexInSheet=4|OwnerPartId=-1|Location.X=1009|Location.Y=252|Color=8388608|FontID=7|IsHidden=T|Name=DATE
|RECORD=41|OwnerIndex=846|IndexInSheet=5|OwnerPartId=-1|Location.X=1009|Location.Y=252|Color=8388608|FontID=7|IsHidden=T|Text=150C|Name=MAXTEMP
|RECORD=41|OwnerIndex=846|IndexInSheet=6|OwnerPartId=-1|Location.X=1009|Location.Y=252|Color=8388608|FontID=7|IsHidden=T|Text=-55C|Name=MINTEMP
|RECORD=41|OwnerIndex=846|IndexInSheet=7|OwnerPartId=-1|Location.X=1009|Location.Y=252|Color=8388608|FontID=7|IsHidden=T|Text=SERIES|Name=OTHER
|RECORD=41|OwnerIndex=846|IndexInSheet=8|OwnerPartId=-1|Location.X=1009|Location.Y=252|Color=8388608|FontID=7|IsHidden=T|Text=SCHOTTKY|Name=P1
|RECORD=41|OwnerIndex=846|IndexInSheet=9|OwnerPartId=-1|Location.X=1009|Location.Y=252|Color=8388608|FontID=7|IsHidden=T|Text=30V|Name=P2
|RECORD=41|OwnerIndex=846|IndexInSheet=10|OwnerPartId=-1|Location.X=1009|Location.Y=252|Color=8388608|FontID=7|IsHidden=T|Text=200mA,200mW|Name=P3
|RECORD=41|OwnerIndex=846|IndexInSheet=11|OwnerPartId=-1|Location.X=1009|Location.Y=252|Color=8388608|FontID=7|IsHidden=T|Text=SC-70|Name=SIZE
|RECORD=41|OwnerIndex=846|IndexInSheet=12|OwnerPartId=-1|Location.X=1009|Location.Y=252|Color=8388608|FontID=7|IsHidden=T|Name=SUB
|RECORD=41|OwnerIndex=846|IndexInSheet=13|OwnerPartId=-1|Location.X=1009|Location.Y=252|Color=8388608|FontID=1|IsHidden=T|Text=*|Name=SHEETPART
|RECORD=41|OwnerIndex=846|IndexInSheet=14|OwnerPartId=-1|Location.X=1009|Location.Y=252|Color=8388608|FontID=1|IsHidden=T|Text=DIO, SCHOTTKY, BAT54S, DUAL SERIES, 30V, 200MA, SC-70|Name=DESC
|RECORD=41|OwnerIndex=846|IndexInSheet=15|OwnerPartId=-1|Location.X=1009|Location.Y=252|Color=8388608|FontID=1|IsHidden=T|Text=Digi-Key|Name=Supplier 1|ReadOnlyState=3
|RECORD=41|OwnerIndex=846|IndexInSheet=16|OwnerPartId=-1|Location.X=1009|Location.Y=252|Color=8388608|FontID=1|IsHidden=T|Text=BAT54SWQ-7-FDICT-ND|Name=Supplier Part Number 1|ReadOnlyState=3
|RECORD=41|OwnerIndex=846|IndexInSheet=17|OwnerPartId=-1|Location.X=1051|Location.Y=205|Color=8388608|FontID=7|Text=BAT54SW|Name=VALUE
|RECORD=2|OwnerIndex=846|OwnerPartId=1|FormalType=1|Electrical=4|PinConglomerate=51|PinLength=20|Location.X=1040|Location.Y=200|Name=2|Designator=2|SwapIdPin=1|SwapIDPart=1|PinPropagationDelay=0.000000E+000
|RECORD=2|OwnerIndex=846|OwnerPartId=1|FormalType=1|Electrical=4|PinConglomerate=49|PinLength=20|Location.X=1030|Location.Y=230|Name=3|Designator=3|SwapIdPin=2|SwapIDPart=1|PinPropagationDelay=0.000000E+000
|RECORD=2|OwnerIndex=846|OwnerPartId=1|FormalType=1|Electrical=4|PinConglomerate=51|PinLength=20|Location.X=1020|Location.Y=200|Name=1|Designator=1|SwapIdPin=3|SwapIDPart=1|PinPropagationDelay=0.000000E+000
|RECORD=13|OwnerIndex=846|IsNotAccesible=T|IndexInSheet=21|OwnerPartId=1|Location.X=1020|Location.Y=230|Corner.X=1020|Corner.Y=220|LineWidth=1|Color=16711680
|RECORD=13|OwnerIndex=846|IsNotAccesible=T|IndexInSheet=22|OwnerPartId=1|Location.X=1030|Location.Y=208|Corner.X=1050|Corner.Y=208|LineWidth=1|Color=16711680
|RECORD=13|OwnerIndex=846|IsNotAccesible=T|IndexInSheet=23|OwnerPartId=1|Location.X=1040|Location.Y=210|Corner.X=1040|Corner.Y=200|LineWidth=1|Color=16711680
|RECORD=13|OwnerIndex=846|IsNotAccesible=T|IndexInSheet=24|OwnerPartId=1|Location.X=1040|Location.Y=230|Corner.X=1040|Corner.Y=220|LineWidth=1|Color=16711680
|RECORD=13|OwnerIndex=846|IsNotAccesible=T|IndexInSheet=25|OwnerPartId=1|Location.X=1020|Location.Y=210|Corner.X=1020|Corner.Y=200|LineWidth=1|Color=16711680
|RECORD=13|OwnerIndex=846|IsNotAccesible=T|IndexInSheet=26|OwnerPartId=1|Location.X=1010|Location.Y=220|Corner.X=1030|Corner.Y=220|LineWidth=1|Color=16711680
|RECORD=7|OwnerIndex=846|IsNotAccesible=T|IndexInSheet=27|OwnerPartId=1|LineWidth=1|Color=16711680|AreaColor=16711680|IsSolid=T|LocationCount=3|X1=1020|Y1=220|Y1_Frac=20000|X2=1012|X2_Frac=50000|Y2=207|Y2_Frac=70000|X3=1027|X3_Frac=50000|Y3=207|Y3_Frac=70000
|RECORD=7|OwnerIndex=846|IsNotAccesible=T|IndexInSheet=28|OwnerPartId=1|LineWidth=1|Color=16711680|AreaColor=16711680|IsSolid=T|LocationCount=3|X1=1040|Y1=208|X2=1047|X2_Frac=50000|Y2=220|Y2_Frac=50000|X3=1032|X3_Frac=50000|Y3=220|Y3_Frac=50000
|RECORD=6|OwnerIndex=846|IsNotAccesible=T|IndexInSheet=29|OwnerPartId=1|LineWidth=1|Color=16711680|LocationCount=2|X1=1020|Y1=230|X2=1040|Y2=230
|RECORD=41|OwnerIndex=846|IndexInSheet=30|OwnerPartId=-1|Location.X=1009|Location.Y=252|Color=8388608|FontID=1|IsHidden=T|Text=<VALENTIUM>|Name=VALENTIUM PART NUM
|RECORD=34|OwnerIndex=846|IndexInSheet=-1|OwnerPartId=-1|Location.X=1051|Location.Y=217|Color=8388608|FontID=1|Text=D8|Name=Designator|ReadOnlyState=1
|RECORD=41|OwnerIndex=846|IndexInSheet=-1|OwnerPartId=-1|Location.X=1009|Location.Y=252|Color=8388608|FontID=1|IsHidden=T|Text=BAT54SW|Name=Comment
|RECORD=44|OwnerIndex=846
|RECORD=45|OwnerIndex=883|IndexInSheet=-1|Description=SOT323-3 (SC70), 3-Leads, Body 2.00x2.10mm, Pitch 0.65mm, IPC Medium Density|UseComponentLibrary=T|ModelName=SOT65P210X110-3N|ModelType=PCBLIB|DatafileCount=1|ModelDatafileEntity0=SOT65P210X110-3N|ModelDatafileKind0=PCBLib|IsCurrent=T|DatalinksLocked=T|DatabaseDatalinksLocked=T|IntegratedModel=T|DatabaseModel=T
|RECORD=46|OwnerIndex=884
|RECORD=48|OwnerIndex=884
|RECORD=1|LibReference=BAT54SW|ComponentDescription=DIO, SCHOTTKY, BAT54S, DUAL SERIES, 30V, 200MA, SC-70|PartCount=2|DisplayModeCount=1|IndexInSheet=70|OwnerPartId=-1|Location.X=880|Location.Y=180|Orientation=1|CurrentPartId=1|LibraryPath=*|SourceLibraryName=Passives.IntLib|TargetFileName=*|AreaColor=11599871|Color=128|PartIDLocked=F|DesignItemId=BAT54SW|AllPinCount=3
|RECORD=41|OwnerIndex=887|OwnerPartId=-1|Location.X=869|Location.Y=252|Color=8388608|FontID=7|IsHidden=T|Text=BAT54SWQ-7-F|Name=MFG PART NUM
|RECORD=41|OwnerIndex=887|IndexInSheet=1|OwnerPartId=-1|Location.X=869|Location.Y=252|Color=8388608|FontID=7|IsHidden=T|Text=9/4/2013|Name=MODIFY DATE
|RECORD=41|OwnerIndex=887|IndexInSheet=2|OwnerPartId=-1|Location.X=869|Location.Y=252|Color=8388608|FontID=7|IsHidden=T|Text=DIODES INC|Name=MFG NAME
|RECORD=41|OwnerIndex=887|IndexInSheet=3|OwnerPartId=-1|Location.X=869|Location.Y=252|Color=8388608|FontID=7|IsHidden=T|Text=DIO, SCHOTTKY|Name=CATEGORY
|RECORD=41|OwnerIndex=887|IndexInSheet=4|OwnerPartId=-1|Location.X=869|Location.Y=252|Color=8388608|FontID=7|IsHidden=T|Name=DATE
|RECORD=41|OwnerIndex=887|IndexInSheet=5|OwnerPartId=-1|Location.X=869|Location.Y=252|Color=8388608|FontID=7|IsHidden=T|Text=150C|Name=MAXTEMP
|RECORD=41|OwnerIndex=887|IndexInSheet=6|OwnerPartId=-1|Location.X=869|Location.Y=252|Color=8388608|FontID=7|IsHidden=T|Text=-55C|Name=MINTEMP
|RECORD=41|OwnerIndex=887|IndexInSheet=7|OwnerPartId=-1|Location.X=869|Location.Y=252|Color=8388608|FontID=7|IsHidden=T|Text=SERIES|Name=OTHER
|RECORD=41|OwnerIndex=887|IndexInSheet=8|OwnerPartId=-1|Location.X=869|Location.Y=252|Color=8388608|FontID=7|IsHidden=T|Text=SCHOTTKY|Name=P1
|RECORD=41|OwnerIndex=887|IndexInSheet=9|OwnerPartId=-1|Location.X=869|Location.Y=252|Color=8388608|FontID=7|IsHidden=T|Text=30V|Name=P2
|RECORD=41|OwnerIndex=887|IndexInSheet=10|OwnerPartId=-1|Location.X=869|Location.Y=252|Color=8388608|FontID=7|IsHidden=T|Text=200mA,200mW|Name=P3
|RECORD=41|OwnerIndex=887|IndexInSheet=11|OwnerPartId=-1|Location.X=869|Location.Y=252|Color=8388608|FontID=7|IsHidden=T|Text=SC-70|Name=SIZE
|RECORD=41|OwnerIndex=887|IndexInSheet=12|OwnerPartId=-1|Location.X=869|Location.Y=252|Color=8388608|FontID=7|IsHidden=T|Name=SUB
|RECORD=41|OwnerIndex=887|IndexInSheet=13|OwnerPartId=-1|Location.X=869|Location.Y=252|Color=8388608|FontID=1|IsHidden=T|Text=*|Name=SHEETPART
|RECORD=41|OwnerIndex=887|IndexInSheet=14|OwnerPartId=-1|Location.X=869|Location.Y=252|Color=8388608|FontID=1|IsHidden=T|Text=DIO, SCHOTTKY, BAT54S, DUAL SERIES, 30V, 200MA, SC-70|Name=DESC
|RECORD=41|OwnerIndex=887|IndexInSheet=15|OwnerPartId=-1|Location.X=869|Location.Y=252|Color=8388608|FontID=1|IsHidden=T|Text=Digi-Key|Name=Supplier 1|ReadOnlyState=3
|RECORD=41|OwnerIndex=887|IndexInSheet=16|OwnerPartId=-1|Location.X=869|Location.Y=252|Color=8388608|FontID=1|IsHidden=T|Text=BAT54SWQ-7-FDICT-ND|Name=Supplier Part Number 1|ReadOnlyState=3
|RECORD=41|OwnerIndex=887|IndexInSheet=17|OwnerPartId=-1|Location.X=911|Location.Y=205|Color=8388608|FontID=7|Text=BAT54SW|Name=VALUE
|RECORD=2|OwnerIndex=887|OwnerPartId=1|FormalType=1|Electrical=4|PinConglomerate=51|PinLength=20|Location.X=900|Location.Y=200|Name=2|Designator=2|SwapIdPin=1|SwapIDPart=1|PinPropagationDelay=0.000000E+000
|RECORD=2|OwnerIndex=887|OwnerPartId=1|FormalType=1|Electrical=4|PinConglomerate=49|PinLength=20|Location.X=890|Location.Y=230|Name=3|Designator=3|SwapIdPin=2|SwapIDPart=1|PinPropagationDelay=0.000000E+000
|RECORD=2|OwnerIndex=887|OwnerPartId=1|FormalType=1|Electrical=4|PinConglomerate=51|PinLength=20|Location.X=880|Location.Y=200|Name=1|Designator=1|SwapIdPin=3|SwapIDPart=1|PinPropagationDelay=0.000000E+000
|RECORD=13|OwnerIndex=887|IsNotAccesible=T|IndexInSheet=21|OwnerPartId=1|Location.X=880|Location.Y=230|Corner.X=880|Corner.Y=220|LineWidth=1|Color=16711680
|RECORD=13|OwnerIndex=887|IsNotAccesible=T|IndexInSheet=22|OwnerPartId=1|Location.X=890|Location.Y=208|Corner.X=910|Corner.Y=208|LineWidth=1|Color=16711680
|RECORD=13|OwnerIndex=887|IsNotAccesible=T|IndexInSheet=23|OwnerPartId=1|Location.X=900|Location.Y=210|Corner.X=900|Corner.Y=200|LineWidth=1|Color=16711680
|RECORD=13|OwnerIndex=887|IsNotAccesible=T|IndexInSheet=24|OwnerPartId=1|Location.X=900|Location.Y=230|Corner.X=900|Corner.Y=220|LineWidth=1|Color=16711680
|RECORD=13|OwnerIndex=887|IsNotAccesible=T|IndexInSheet=25|OwnerPartId=1|Location.X=880|Location.Y=210|Corner.X=880|Corner.Y=200|LineWidth=1|Color=16711680
|RECORD=13|OwnerIndex=887|IsNotAccesible=T|IndexInSheet=26|OwnerPartId=1|Location.X=870|Location.Y=220|Corner.X=890|Corner.Y=220|LineWidth=1|Color=16711680
|RECORD=7|OwnerIndex=887|IsNotAccesible=T|IndexInSheet=27|OwnerPartId=1|LineWidth=1|Color=16711680|AreaColor=16711680|IsSolid=T|LocationCount=3|X1=880|Y1=220|Y1_Frac=20000|X2=872|X2_Frac=50000|Y2=207|Y2_Frac=70000|X3=887|X3_Frac=50000|Y3=207|Y3_Frac=70000
|RECORD=7|OwnerIndex=887|IsNotAccesible=T|IndexInSheet=28|OwnerPartId=1|LineWidth=1|Color=16711680|AreaColor=16711680|IsSolid=T|LocationCount=3|X1=900|Y1=208|X2=907|X2_Frac=50000|Y2=220|Y2_Frac=50000|X3=892|X3_Frac=50000|Y3=220|Y3_Frac=50000
|RECORD=6|OwnerIndex=887|IsNotAccesible=T|IndexInSheet=29|OwnerPartId=1|LineWidth=1|Color=16711680|LocationCount=2|X1=880|Y1=230|X2=900|Y2=230
|RECORD=41|OwnerIndex=887|IndexInSheet=30|OwnerPartId=-1|Location.X=869|Location.Y=252|Color=8388608|FontID=1|IsHidden=T|Text=<VALENTIUM>|Name=VALENTIUM PART NUM
|RECORD=34|OwnerIndex=887|IndexInSheet=-1|OwnerPartId=-1|Location.X=911|Location.Y=217|Color=8388608|FontID=1|Text=D7|Name=Designator|ReadOnlyState=1
|RECORD=41|OwnerIndex=887|IndexInSheet=-1|OwnerPartId=-1|Location.X=869|Location.Y=252|Color=8388608|FontID=1|IsHidden=T|Text=BAT54SW|Name=Comment
|RECORD=44|OwnerIndex=887
|RECORD=45|OwnerIndex=924|IndexInSheet=-1|Description=SOT323-3 (SC70), 3-Leads, Body 2.00x2.10mm, Pitch 0.65mm, IPC Medium Density|UseComponentLibrary=T|ModelName=SOT65P210X110-3N|ModelType=PCBLIB|DatafileCount=1|ModelDatafileEntity0=SOT65P210X110-3N|ModelDatafileKind0=PCBLib|IsCurrent=T|DatalinksLocked=T|DatabaseDatalinksLocked=T|IntegratedModel=T|DatabaseModel=T
|RECORD=46|OwnerIndex=925
|RECORD=48|OwnerIndex=925
|RECORD=1|LibReference=BAT54SW|ComponentDescription=DIO, SCHOTTKY, BAT54S, DUAL SERIES, 30V, 200MA, SC-70|PartCount=2|DisplayModeCount=1|IndexInSheet=71|OwnerPartId=-1|Location.X=740|Location.Y=180|Orientation=1|CurrentPartId=1|LibraryPath=*|SourceLibraryName=Passives.IntLib|TargetFileName=*|AreaColor=11599871|Color=128|PartIDLocked=F|DesignItemId=BAT54SW|AllPinCount=3
|RECORD=41|OwnerIndex=928|OwnerPartId=-1|Location.X=729|Location.Y=252|Color=8388608|FontID=7|IsHidden=T|Text=BAT54SWQ-7-F|Name=MFG PART NUM
|RECORD=41|OwnerIndex=928|IndexInSheet=1|OwnerPartId=-1|Location.X=729|Location.Y=252|Color=8388608|FontID=7|IsHidden=T|Text=9/4/2013|Name=MODIFY DATE
|RECORD=41|OwnerIndex=928|IndexInSheet=2|OwnerPartId=-1|Location.X=729|Location.Y=252|Color=8388608|FontID=7|IsHidden=T|Text=DIODES INC|Name=MFG NAME
|RECORD=41|OwnerIndex=928|IndexInSheet=3|OwnerPartId=-1|Location.X=729|Location.Y=252|Color=8388608|FontID=7|IsHidden=T|Text=DIO, SCHOTTKY|Name=CATEGORY
|RECORD=41|OwnerIndex=928|IndexInSheet=4|OwnerPartId=-1|Location.X=729|Location.Y=252|Color=8388608|FontID=7|IsHidden=T|Name=DATE
|RECORD=41|OwnerIndex=928|IndexInSheet=5|OwnerPartId=-1|Location.X=729|Location.Y=252|Color=8388608|FontID=7|IsHidden=T|Text=150C|Name=MAXTEMP
|RECORD=41|OwnerIndex=928|IndexInSheet=6|OwnerPartId=-1|Location.X=729|Location.Y=252|Color=8388608|FontID=7|IsHidden=T|Text=-55C|Name=MINTEMP
|RECORD=41|OwnerIndex=928|IndexInSheet=7|OwnerPartId=-1|Location.X=729|Location.Y=252|Color=8388608|FontID=7|IsHidden=T|Text=SERIES|Name=OTHER
|RECORD=41|OwnerIndex=928|IndexInSheet=8|OwnerPartId=-1|Location.X=729|Location.Y=252|Color=8388608|FontID=7|IsHidden=T|Text=SCHOTTKY|Name=P1
|RECORD=41|OwnerIndex=928|IndexInSheet=9|OwnerPartId=-1|Location.X=729|Location.Y=252|Color=8388608|FontID=7|IsHidden=T|Text=30V|Name=P2
|RECORD=41|OwnerIndex=928|IndexInSheet=10|OwnerPartId=-1|Location.X=729|Location.Y=252|Color=8388608|FontID=7|IsHidden=T|Text=200mA,200mW|Name=P3
|RECORD=41|OwnerIndex=928|IndexInSheet=11|OwnerPartId=-1|Location.X=729|Location.Y=252|Color=8388608|FontID=7|IsHidden=T|Text=SC-70|Name=SIZE
|RECORD=41|OwnerIndex=928|IndexInSheet=12|OwnerPartId=-1|Location.X=729|Location.Y=252|Color=8388608|FontID=7|IsHidden=T|Name=SUB
|RECORD=41|OwnerIndex=928|IndexInSheet=13|OwnerPartId=-1|Location.X=729|Location.Y=252|Color=8388608|FontID=1|IsHidden=T|Text=*|Name=SHEETPART
|RECORD=41|OwnerIndex=928|IndexInSheet=14|OwnerPartId=-1|Location.X=729|Location.Y=252|Color=8388608|FontID=1|IsHidden=T|Text=DIO, SCHOTTKY, BAT54S, DUAL SERIES, 30V, 200MA, SC-70|Name=DESC
|RECORD=41|OwnerIndex=928|IndexInSheet=15|OwnerPartId=-1|Location.X=729|Location.Y=252|Color=8388608|FontID=1|IsHidden=T|Text=Digi-Key|Name=Supplier 1|ReadOnlyState=3
|RECORD=41|OwnerIndex=928|IndexInSheet=16|OwnerPartId=-1|Location.X=729|Location.Y=252|Color=8388608|FontID=1|IsHidden=T|Text=BAT54SWQ-7-FDICT-ND|Name=Supplier Part Number 1|ReadOnlyState=3
|RECORD=41|OwnerIndex=928|IndexInSheet=17|OwnerPartId=-1|Location.X=771|Location.Y=205|Color=8388608|FontID=7|Text=BAT54SW|Name=VALUE
|RECORD=2|OwnerIndex=928|OwnerPartId=1|FormalType=1|Electrical=4|PinConglomerate=51|PinLength=20|Location.X=760|Location.Y=200|Name=2|Designator=2|SwapIdPin=1|SwapIDPart=1|PinPropagationDelay=0.000000E+000
|RECORD=2|OwnerIndex=928|OwnerPartId=1|FormalType=1|Electrical=4|PinConglomerate=49|PinLength=20|Location.X=750|Location.Y=230|Name=3|Designator=3|SwapIdPin=2|SwapIDPart=1|PinPropagationDelay=0.000000E+000
|RECORD=2|OwnerIndex=928|OwnerPartId=1|FormalType=1|Electrical=4|PinConglomerate=51|PinLength=20|Location.X=740|Location.Y=200|Name=1|Designator=1|SwapIdPin=3|SwapIDPart=1|PinPropagationDelay=0.000000E+000
|RECORD=13|OwnerIndex=928|IsNotAccesible=T|IndexInSheet=21|OwnerPartId=1|Location.X=740|Location.Y=230|Corner.X=740|Corner.Y=220|LineWidth=1|Color=16711680
|RECORD=13|OwnerIndex=928|IsNotAccesible=T|IndexInSheet=22|OwnerPartId=1|Location.X=750|Location.Y=208|Corner.X=770|Corner.Y=208|LineWidth=1|Color=16711680
|RECORD=13|OwnerIndex=928|IsNotAccesible=T|IndexInSheet=23|OwnerPartId=1|Location.X=760|Location.Y=210|Corner.X=760|Corner.Y=200|LineWidth=1|Color=16711680
|RECORD=13|OwnerIndex=928|IsNotAccesible=T|IndexInSheet=24|OwnerPartId=1|Location.X=760|Location.Y=230|Corner.X=760|Corner.Y=220|LineWidth=1|Color=16711680
|RECORD=13|OwnerIndex=928|IsNotAccesible=T|IndexInSheet=25|OwnerPartId=1|Location.X=740|Location.Y=210|Corner.X=740|Corner.Y=200|LineWidth=1|Color=16711680
|RECORD=13|OwnerIndex=928|IsNotAccesible=T|IndexInSheet=26|OwnerPartId=1|Location.X=730|Location.Y=220|Corner.X=750|Corner.Y=220|LineWidth=1|Color=16711680
|RECORD=7|OwnerIndex=928|IsNotAccesible=T|IndexInSheet=27|OwnerPartId=1|LineWidth=1|Color=16711680|AreaColor=16711680|IsSolid=T|LocationCount=3|X1=740|Y1=220|Y1_Frac=20000|X2=732|X2_Frac=50000|Y2=207|Y2_Frac=70000|X3=747|X3_Frac=50000|Y3=207|Y3_Frac=70000
|RECORD=7|OwnerIndex=928|IsNotAccesible=T|IndexInSheet=28|OwnerPartId=1|LineWidth=1|Color=16711680|AreaColor=16711680|IsSolid=T|LocationCount=3|X1=760|Y1=208|X2=767|X2_Frac=50000|Y2=220|Y2_Frac=50000|X3=752|X3_Frac=50000|Y3=220|Y3_Frac=50000
|RECORD=6|OwnerIndex=928|IsNotAccesible=T|IndexInSheet=29|OwnerPartId=1|LineWidth=1|Color=16711680|LocationCount=2|X1=740|Y1=230|X2=760|Y2=230
|RECORD=41|OwnerIndex=928|IndexInSheet=30|OwnerPartId=-1|Location.X=729|Location.Y=252|Color=8388608|FontID=1|IsHidden=T|Text=<VALENTIUM>|Name=VALENTIUM PART NUM
|RECORD=34|OwnerIndex=928|IndexInSheet=-1|OwnerPartId=-1|Location.X=771|Location.Y=217|Color=8388608|FontID=1|Text=D6|Name=Designator|ReadOnlyState=1
|RECORD=41|OwnerIndex=928|IndexInSheet=-1|OwnerPartId=-1|Location.X=729|Location.Y=252|Color=8388608|FontID=1|IsHidden=T|Text=BAT54SW|Name=Comment
|RECORD=44|OwnerIndex=928
|RECORD=45|OwnerIndex=965|IndexInSheet=-1|Description=SOT323-3 (SC70), 3-Leads, Body 2.00x2.10mm, Pitch 0.65mm, IPC Medium Density|UseComponentLibrary=T|ModelName=SOT65P210X110-3N|ModelType=PCBLIB|DatafileCount=1|ModelDatafileEntity0=SOT65P210X110-3N|ModelDatafileKind0=PCBLib|IsCurrent=T|DatalinksLocked=T|DatabaseDatalinksLocked=T|IntegratedModel=T|DatabaseModel=T
|RECORD=46|OwnerIndex=966
|RECORD=48|OwnerIndex=966
|RECORD=1|LibReference=BAT54SW|ComponentDescription=DIO, SCHOTTKY, BAT54S, DUAL SERIES, 30V, 200MA, SC-70|PartCount=2|DisplayModeCount=1|IndexInSheet=72|OwnerPartId=-1|Location.X=600|Location.Y=180|Orientation=1|CurrentPartId=1|LibraryPath=*|SourceLibraryName=Passives.IntLib|TargetFileName=*|AreaColor=11599871|Color=128|PartIDLocked=F|DesignItemId=BAT54SW|AllPinCount=3
|RECORD=41|OwnerIndex=969|OwnerPartId=-1|Location.X=589|Location.Y=252|Color=8388608|FontID=7|IsHidden=T|Text=BAT54SWQ-7-F|Name=MFG PART NUM
|RECORD=41|OwnerIndex=969|IndexInSheet=1|OwnerPartId=-1|Location.X=589|Location.Y=252|Color=8388608|FontID=7|IsHidden=T|Text=9/4/2013|Name=MODIFY DATE
|RECORD=41|OwnerIndex=969|IndexInSheet=2|OwnerPartId=-1|Location.X=589|Location.Y=252|Color=8388608|FontID=7|IsHidden=T|Text=DIODES INC|Name=MFG NAME
|RECORD=41|OwnerIndex=969|IndexInSheet=3|OwnerPartId=-1|Location.X=589|Location.Y=252|Color=8388608|FontID=7|IsHidden=T|Text=DIO, SCHOTTKY|Name=CATEGORY
|RECORD=41|OwnerIndex=969|IndexInSheet=4|OwnerPartId=-1|Location.X=589|Location.Y=252|Color=8388608|FontID=7|IsHidden=T|Name=DATE
|RECORD=41|OwnerIndex=969|IndexInSheet=5|OwnerPartId=-1|Location.X=589|Location.Y=252|Color=8388608|FontID=7|IsHidden=T|Text=150C|Name=MAXTEMP
|RECORD=41|OwnerIndex=969|IndexInSheet=6|OwnerPartId=-1|Location.X=589|Location.Y=252|Color=8388608|FontID=7|IsHidden=T|Text=-55C|Name=MINTEMP
|RECORD=41|OwnerIndex=969|IndexInSheet=7|OwnerPartId=-1|Location.X=589|Location.Y=252|Color=8388608|FontID=7|IsHidden=T|Text=SERIES|Name=OTHER
|RECORD=41|OwnerIndex=969|IndexInSheet=8|OwnerPartId=-1|Location.X=589|Location.Y=252|Color=8388608|FontID=7|IsHidden=T|Text=SCHOTTKY|Name=P1
|RECORD=41|OwnerIndex=969|IndexInSheet=9|OwnerPartId=-1|Location.X=589|Location.Y=252|Color=8388608|FontID=7|IsHidden=T|Text=30V|Name=P2
|RECORD=41|OwnerIndex=969|IndexInSheet=10|OwnerPartId=-1|Location.X=589|Location.Y=252|Color=8388608|FontID=7|IsHidden=T|Text=200mA,200mW|Name=P3
|RECORD=41|OwnerIndex=969|IndexInSheet=11|OwnerPartId=-1|Location.X=589|Location.Y=252|Color=8388608|FontID=7|IsHidden=T|Text=SC-70|Name=SIZE
|RECORD=41|OwnerIndex=969|IndexInSheet=12|OwnerPartId=-1|Location.X=589|Location.Y=252|Color=8388608|FontID=7|IsHidden=T|Name=SUB
|RECORD=41|OwnerIndex=969|IndexInSheet=13|OwnerPartId=-1|Location.X=589|Location.Y=252|Color=8388608|FontID=1|IsHidden=T|Text=*|Name=SHEETPART
|RECORD=41|OwnerIndex=969|IndexInSheet=14|OwnerPartId=-1|Location.X=589|Location.Y=252|Color=8388608|FontID=1|IsHidden=T|Text=DIO, SCHOTTKY, BAT54S, DUAL SERIES, 30V, 200MA, SC-70|Name=DESC
|RECORD=41|OwnerIndex=969|IndexInSheet=15|OwnerPartId=-1|Location.X=589|Location.Y=252|Color=8388608|FontID=1|IsHidden=T|Text=Digi-Key|Name=Supplier 1|ReadOnlyState=3
|RECORD=41|OwnerIndex=969|IndexInSheet=16|OwnerPartId=-1|Location.X=589|Location.Y=252|Color=8388608|FontID=1|IsHidden=T|Text=BAT54SWQ-7-FDICT-ND|Name=Supplier Part Number 1|ReadOnlyState=3
|RECORD=41|OwnerIndex=969|IndexInSheet=17|OwnerPartId=-1|Location.X=631|Location.Y=205|Color=8388608|FontID=7|Text=BAT54SW|Name=VALUE
|RECORD=2|OwnerIndex=969|OwnerPartId=1|FormalType=1|Electrical=4|PinConglomerate=51|PinLength=20|Location.X=620|Location.Y=200|Name=2|Designator=2|SwapIdPin=1|SwapIDPart=1|PinPropagationDelay=0.000000E+000
|RECORD=2|OwnerIndex=969|OwnerPartId=1|FormalType=1|Electrical=4|PinConglomerate=49|PinLength=20|Location.X=610|Location.Y=230|Name=3|Designator=3|SwapIdPin=2|SwapIDPart=1|PinPropagationDelay=0.000000E+000
|RECORD=2|OwnerIndex=969|OwnerPartId=1|FormalType=1|Electrical=4|PinConglomerate=51|PinLength=20|Location.X=600|Location.Y=200|Name=1|Designator=1|SwapIdPin=3|SwapIDPart=1|PinPropagationDelay=0.000000E+000
|RECORD=13|OwnerIndex=969|IsNotAccesible=T|IndexInSheet=21|OwnerPartId=1|Location.X=600|Location.Y=230|Corner.X=600|Corner.Y=220|LineWidth=1|Color=16711680
|RECORD=13|OwnerIndex=969|IsNotAccesible=T|IndexInSheet=22|OwnerPartId=1|Location.X=610|Location.Y=208|Corner.X=630|Corner.Y=208|LineWidth=1|Color=16711680
|RECORD=13|OwnerIndex=969|IsNotAccesible=T|IndexInSheet=23|OwnerPartId=1|Location.X=620|Location.Y=210|Corner.X=620|Corner.Y=200|LineWidth=1|Color=16711680
|RECORD=13|OwnerIndex=969|IsNotAccesible=T|IndexInSheet=24|OwnerPartId=1|Location.X=620|Location.Y=230|Corner.X=620|Corner.Y=220|LineWidth=1|Color=16711680
|RECORD=13|OwnerIndex=969|IsNotAccesible=T|IndexInSheet=25|OwnerPartId=1|Location.X=600|Location.Y=210|Corner.X=600|Corner.Y=200|LineWidth=1|Color=16711680
|RECORD=13|OwnerIndex=969|IsNotAccesible=T|IndexInSheet=26|OwnerPartId=1|Location.X=590|Location.Y=220|Corner.X=610|Corner.Y=220|LineWidth=1|Color=16711680
|RECORD=7|OwnerIndex=969|IsNotAccesible=T|IndexInSheet=27|OwnerPartId=1|LineWidth=1|Color=16711680|AreaColor=16711680|IsSolid=T|LocationCount=3|X1=600|Y1=220|Y1_Frac=20000|X2=592|X2_Frac=50000|Y2=207|Y2_Frac=70000|X3=607|X3_Frac=50000|Y3=207|Y3_Frac=70000
|RECORD=7|OwnerIndex=969|IsNotAccesible=T|IndexInSheet=28|OwnerPartId=1|LineWidth=1|Color=16711680|AreaColor=16711680|IsSolid=T|LocationCount=3|X1=620|Y1=208|X2=627|X2_Frac=50000|Y2=220|Y2_Frac=50000|X3=612|X3_Frac=50000|Y3=220|Y3_Frac=50000
|RECORD=6|OwnerIndex=969|IsNotAccesible=T|IndexInSheet=29|OwnerPartId=1|LineWidth=1|Color=16711680|LocationCount=2|X1=600|Y1=230|X2=620|Y2=230
|RECORD=41|OwnerIndex=969|IndexInSheet=30|OwnerPartId=-1|Location.X=589|Location.Y=252|Color=8388608|FontID=1|IsHidden=T|Text=<VALENTIUM>|Name=VALENTIUM PART NUM
|RECORD=34|OwnerIndex=969|IndexInSheet=-1|OwnerPartId=-1|Location.X=631|Location.Y=217|Color=8388608|FontID=1|Text=D5|Name=Designator|ReadOnlyState=1
|RECORD=41|OwnerIndex=969|IndexInSheet=-1|OwnerPartId=-1|Location.X=589|Location.Y=252|Color=8388608|FontID=1|IsHidden=T|Text=BAT54SW|Name=Comment
|RECORD=44|OwnerIndex=969
|RECORD=45|OwnerIndex=1006|IndexInSheet=-1|Description=SOT323-3 (SC70), 3-Leads, Body 2.00x2.10mm, Pitch 0.65mm, IPC Medium Density|UseComponentLibrary=T|ModelName=SOT65P210X110-3N|ModelType=PCBLIB|DatafileCount=1|ModelDatafileEntity0=SOT65P210X110-3N|ModelDatafileKind0=PCBLib|IsCurrent=T|DatalinksLocked=T|DatabaseDatalinksLocked=T|IntegratedModel=T|DatabaseModel=T
|RECORD=46|OwnerIndex=1007
|RECORD=48|OwnerIndex=1007
|RECORD=25|IndexInSheet=73|OwnerPartId=-1|Location.X=940|Location.Y=950|Color=128|FontID=1|Text=PRSNT
|RECORD=25|IndexInSheet=74|OwnerPartId=-1|Location.X=600|Location.Y=780|Color=128|FontID=1|Text=PRSNT
|RECORD=25|IndexInSheet=75|OwnerPartId=-1|Location.X=600|Location.Y=640|Color=128|FontID=1|Text=PRSNT
|RECORD=17|IndexInSheet=76|OwnerPartId=-1|ShowNetName=T|Location.X=620|Location.Y=260|Color=255|FontID=1|Text=FPGA_TCK|IsCrossSheetConnector=T
|RECORD=17|IndexInSheet=77|OwnerPartId=-1|ShowNetName=T|Location.X=760|Location.Y=260|Color=255|FontID=1|Text=FPGA_TDO|IsCrossSheetConnector=T
|RECORD=17|IndexInSheet=78|OwnerPartId=-1|ShowNetName=T|Location.X=900|Location.Y=260|Color=255|FontID=1|Text=FPGA_TMS|IsCrossSheetConnector=T
|RECORD=17|IndexInSheet=79|OwnerPartId=-1|ShowNetName=T|Location.X=1040|Location.Y=260|Color=255|FontID=1|Text=FPGA_TDI|IsCrossSheetConnector=T
|RECORD=27|IndexInSheet=80|OwnerPartId=-1|LineWidth=1|Color=8388608|LocationCount=2|X1=740|Y1=690|X2=740|Y2=700
|RECORD=27|IndexInSheet=81|OwnerPartId=-1|LineWidth=1|Color=8388608|LocationCount=2|X1=760|Y1=670|X2=540|Y2=670
|RECORD=27|IndexInSheet=82|OwnerPartId=-1|LineWidth=1|Color=8388608|LocationCount=2|X1=760|Y1=680|X2=540|Y2=680
|RECORD=27|IndexInSheet=83|OwnerPartId=-1|LineWidth=1|Color=8388608|LocationCount=2|X1=760|Y1=710|X2=540|Y2=710
|RECORD=27|IndexInSheet=84|OwnerPartId=-1|LineWidth=1|Color=8388608|LocationCount=2|X1=760|Y1=720|X2=540|Y2=720
|RECORD=27|IndexInSheet=85|OwnerPartId=-1|LineWidth=1|Color=8388608|LocationCount=2|X1=760|Y1=750|X2=540|Y2=750
|RECORD=27|IndexInSheet=86|OwnerPartId=-1|LineWidth=1|Color=8388608|LocationCount=2|X1=760|Y1=760|X2=540|Y2=760
|RECORD=27|IndexInSheet=87|OwnerPartId=-1|LineWidth=1|Color=8388608|LocationCount=2|X1=760|Y1=800|X2=540|Y2=800
|RECORD=27|IndexInSheet=88|OwnerPartId=-1|LineWidth=1|Color=8388608|LocationCount=2|X1=760|Y1=810|X2=540|Y2=810
|RECORD=27|IndexInSheet=89|OwnerPartId=-1|LineWidth=1|Color=8388608|LocationCount=3|X1=760|Y1=880|X2=540|Y2=880|X3=540|Y3=970
|RECORD=27|IndexInSheet=90|OwnerPartId=-1|LineWidth=1|Color=8388608|LocationCount=2|X1=600|Y1=180|X2=590|Y2=180
|RECORD=27|IndexInSheet=91|OwnerPartId=-1|LineWidth=1|Color=8388608|LocationCount=2|X1=670|Y1=640|X2=590|Y2=640
|RECORD=27|IndexInSheet=92|OwnerPartId=-1|LineWidth=1|Color=8388608|LocationCount=2|X1=670|Y1=780|X2=590|Y2=780
|RECORD=27|IndexInSheet=93|OwnerPartId=-1|LineWidth=1|Color=8388608|LocationCount=3|X1=610|Y1=250|X2=610|Y2=260|X3=620|Y3=260
|RECORD=27|IndexInSheet=94|OwnerPartId=-1|LineWidth=1|Color=8388608|LocationCount=3|X1=630|Y1=170|X2=630|Y2=180|X3=620|Y3=180
|RECORD=27|IndexInSheet=95|OwnerPartId=-1|LineWidth=1|Color=8388608|LocationCount=5|X1=760|Y1=930|X2=670|Y2=930|X3=670|Y3=940|X4=670|Y4=950|X5=670|Y5=970
|RECORD=27|IndexInSheet=96|OwnerPartId=-1|LineWidth=1|Color=8388608|LocationCount=2|X1=760|Y1=940|X2=670|Y2=940
|RECORD=27|IndexInSheet=97|OwnerPartId=-1|LineWidth=1|Color=8388608|LocationCount=2|X1=760|Y1=950|X2=670|Y2=950
|RECORD=27|IndexInSheet=98|OwnerPartId=-1|LineWidth=1|Color=8388608|LocationCount=2|X1=760|Y1=640|X2=720|Y2=640
|RECORD=27|IndexInSheet=99|OwnerPartId=-1|LineWidth=1|Color=8388608|LocationCount=2|X1=760|Y1=780|X2=720|Y2=780
|RECORD=27|IndexInSheet=100|OwnerPartId=-1|LineWidth=1|Color=8388608|LocationCount=2|X1=740|Y1=180|X2=730|Y2=180
|RECORD=27|IndexInSheet=101|OwnerPartId=-1|LineWidth=1|Color=8388608|LocationCount=2|X1=790|Y1=340|X2=730|Y2=340
|RECORD=27|IndexInSheet=102|OwnerPartId=-1|LineWidth=1|Color=8388608|LocationCount=2|X1=790|Y1=370|X2=730|Y2=370
|RECORD=27|IndexInSheet=103|OwnerPartId=-1|LineWidth=1|Color=8388608|LocationCount=2|X1=790|Y1=400|X2=730|Y2=400
|RECORD=27|IndexInSheet=104|OwnerPartId=-1|LineWidth=1|Color=8388608|LocationCount=2|X1=790|Y1=430|X2=730|Y2=430
|RECORD=27|IndexInSheet=105|OwnerPartId=-1|LineWidth=1|Color=8388608|LocationCount=2|X1=760|Y1=630|X2=740|Y2=630
|RECORD=27|IndexInSheet=106|OwnerPartId=-1|LineWidth=1|Color=8388608|LocationCount=2|X1=760|Y1=660|X2=740|Y2=660
|RECORD=27|IndexInSheet=107|OwnerPartId=-1|LineWidth=1|Color=8388608|LocationCount=5|X1=760|Y1=690|X2=740|Y2=690|X3=740|Y3=660|X4=740|Y4=630|X5=740|Y5=600
|RECORD=27|IndexInSheet=108|OwnerPartId=-1|LineWidth=1|Color=8388608|LocationCount=2|X1=760|Y1=700|X2=740|Y2=700
|RECORD=27|IndexInSheet=109|OwnerPartId=-1|LineWidth=1|Color=8388608|LocationCount=2|X1=760|Y1=730|X2=740|Y2=730
|RECORD=27|IndexInSheet=110|OwnerPartId=-1|LineWidth=1|Color=8388608|LocationCount=2|X1=760|Y1=740|X2=740|Y2=740
|RECORD=27|IndexInSheet=111|OwnerPartId=-1|LineWidth=1|Color=8388608|LocationCount=2|X1=760|Y1=770|X2=740|Y2=770
|RECORD=27|IndexInSheet=112|OwnerPartId=-1|LineWidth=1|Color=8388608|LocationCount=2|X1=760|Y1=790|X2=740|Y2=790
|RECORD=27|IndexInSheet=113|OwnerPartId=-1|LineWidth=1|Color=8388608|LocationCount=2|X1=760|Y1=820|X2=740|Y2=820
|RECORD=27|IndexInSheet=114|OwnerPartId=-1|LineWidth=1|Color=8388608|LocationCount=2|X1=760|Y1=890|X2=740|Y2=890
|RECORD=27|IndexInSheet=115|OwnerPartId=-1|LineWidth=1|Color=8388608|LocationCount=9|X1=760|Y1=920|X2=740|Y2=920|X3=740|Y3=890|X4=740|Y4=820|X5=740|Y5=790|X6=740|Y6=770|X7=740|Y7=740|X8=740|Y8=730|X9=740|Y9=700
|RECORD=27|IndexInSheet=116|OwnerPartId=-1|LineWidth=1|Color=8388608|LocationCount=3|X1=750|Y1=250|X2=750|Y2=260|X3=760|Y3=260
|RECORD=27|IndexInSheet=117|OwnerPartId=-1|LineWidth=1|Color=8388608|LocationCount=4|X1=760|Y1=180|X2=760|Y2=179|X3=770|Y3=179|X4=770|Y4=169
|RECORD=27|IndexInSheet=118|OwnerPartId=-1|LineWidth=1|Color=8388608|LocationCount=4|X1=880|Y1=350|X2=870|Y2=350|X3=870|Y3=340|X4=840|Y4=340
|RECORD=27|IndexInSheet=119|OwnerPartId=-1|LineWidth=1|Color=8388608|LocationCount=2|X1=880|Y1=370|X2=840|Y2=370
|RECORD=27|IndexInSheet=120|OwnerPartId=-1|LineWidth=1|Color=8388608|LocationCount=4|X1=880|Y1=380|X2=870|Y2=380|X3=870|Y3=400|X4=840|Y4=400
|RECORD=27|IndexInSheet=121|OwnerPartId=-1|LineWidth=1|Color=8388608|LocationCount=3|X1=880|Y1=390|X2=880|Y2=430|X3=840|Y3=430
|RECORD=27|IndexInSheet=122|OwnerPartId=-1|LineWidth=1|Color=8388608|LocationCount=2|X1=880|Y1=180|X2=870|Y2=180
|RECORD=27|IndexInSheet=123|OwnerPartId=-1|LineWidth=1|Color=8388608|LocationCount=3|X1=890|Y1=250|X2=890|Y2=260|X3=900|Y3=260
|RECORD=27|IndexInSheet=124|OwnerPartId=-1|LineWidth=1|Color=8388608|LocationCount=3|X1=910|Y1=170|X2=910|Y2=180|X3=900|Y3=180
|RECORD=27|IndexInSheet=125|OwnerPartId=-1|LineWidth=1|Color=8388608|LocationCount=2|X1=920|Y1=640|X2=940|Y2=640
|RECORD=27|IndexInSheet=126|OwnerPartId=-1|LineWidth=1|Color=8388608|LocationCount=2|X1=920|Y1=650|X2=1080|Y2=650
|RECORD=27|IndexInSheet=127|OwnerPartId=-1|LineWidth=1|Color=8388608|LocationCount=2|X1=920|Y1=660|X2=1040|Y2=660
|RECORD=27|IndexInSheet=128|OwnerPartId=-1|LineWidth=1|Color=8388608|LocationCount=2|X1=920|Y1=670|X2=940|Y2=670
|RECORD=27|IndexInSheet=129|OwnerPartId=-1|LineWidth=1|Color=8388608|LocationCount=2|X1=920|Y1=680|X2=940|Y2=680
|RECORD=27|IndexInSheet=130|OwnerPartId=-1|LineWidth=1|Color=8388608|LocationCount=2|X1=920|Y1=690|X2=1080|Y2=690
|RECORD=27|IndexInSheet=131|OwnerPartId=-1|LineWidth=1|Color=8388608|LocationCount=2|X1=920|Y1=700|X2=1040|Y2=700
|RECORD=27|IndexInSheet=132|OwnerPartId=-1|LineWidth=1|Color=8388608|LocationCount=2|X1=920|Y1=710|X2=940|Y2=710
|RECORD=27|IndexInSheet=133|OwnerPartId=-1|LineWidth=1|Color=8388608|LocationCount=2|X1=920|Y1=720|X2=940|Y2=720
|RECORD=27|IndexInSheet=134|OwnerPartId=-1|LineWidth=1|Color=8388608|LocationCount=2|X1=920|Y1=730|X2=1080|Y2=730
|RECORD=27|IndexInSheet=135|OwnerPartId=-1|LineWidth=1|Color=8388608|LocationCount=2|X1=920|Y1=740|X2=1040|Y2=740
|RECORD=27|IndexInSheet=136|OwnerPartId=-1|LineWidth=1|Color=8388608|LocationCount=2|X1=920|Y1=750|X2=940|Y2=750
|RECORD=27|IndexInSheet=137|OwnerPartId=-1|LineWidth=1|Color=8388608|LocationCount=2|X1=920|Y1=770|X2=940|Y2=770
|RECORD=27|IndexInSheet=138|OwnerPartId=-1|LineWidth=1|Color=8388608|LocationCount=2|X1=920|Y1=780|X2=1080|Y2=780
|RECORD=27|IndexInSheet=139|OwnerPartId=-1|LineWidth=1|Color=8388608|LocationCount=2|X1=920|Y1=790|X2=1010|Y2=790
|RECORD=27|IndexInSheet=140|OwnerPartId=-1|LineWidth=1|Color=8388608|LocationCount=2|X1=920|Y1=800|X2=940|Y2=800
|RECORD=27|IndexInSheet=141|OwnerPartId=-1|LineWidth=1|Color=8388608|LocationCount=2|X1=920|Y1=810|X2=1080|Y2=810
|RECORD=27|IndexInSheet=142|OwnerPartId=-1|LineWidth=1|Color=8388608|LocationCount=2|X1=920|Y1=820|X2=1040|Y2=820
|RECORD=27|IndexInSheet=143|OwnerPartId=-1|LineWidth=1|Color=8388608|LocationCount=2|X1=920|Y1=830|X2=940|Y2=830
|RECORD=27|IndexInSheet=144|OwnerPartId=-1|LineWidth=1|Color=8388608|LocationCount=3|X1=920|Y1=850|X2=1060|Y2=850|X3=1060|Y3=860
|RECORD=27|IndexInSheet=145|OwnerPartId=-1|LineWidth=1|Color=8388608|LocationCount=3|X1=920|Y1=860|X2=1030|Y2=860|X3=1030|Y3=870
|RECORD=27|IndexInSheet=146|OwnerPartId=-1|LineWidth=1|Color=8388608|LocationCount=3|X1=920|Y1=870|X2=1030|Y2=870|X3=1030|Y3=940
|RECORD=27|IndexInSheet=147|OwnerPartId=-1|LineWidth=1|Color=8388608|LocationCount=12|X1=920|Y1=920|X2=940|Y2=920|X3=940|Y3=830|X4=940|Y4=800|X5=940|Y5=770|X6=940|Y6=750|X7=940|Y7=720|X8=940|Y8=710|X9=940|Y9=680|X10=940|Y10=670|X11=940|Y11=640|X12=940|Y12=600
|RECORD=27|IndexInSheet=148|OwnerPartId=-1|LineWidth=1|Color=8388608|LocationCount=3|X1=920|Y1=930|X2=990|Y2=930|X3=990|Y3=940
|RECORD=27|IndexInSheet=149|OwnerPartId=-1|LineWidth=1|Color=8388608|LocationCount=3|X1=920|Y1=940|X2=990|Y2=940|X3=990|Y3=970
|RECORD=27|IndexInSheet=150|OwnerPartId=-1|LineWidth=1|Color=8388608|LocationCount=2|X1=920|Y1=950|X2=980|Y2=950
|RECORD=27|IndexInSheet=151|OwnerPartId=-1|LineWidth=1|Color=8388608|LocationCount=2|X1=980|Y1=350|X2=1010|Y2=350
|RECORD=27|IndexInSheet=152|OwnerPartId=-1|LineWidth=1|Color=8388608|LocationCount=4|X1=980|Y1=370|X2=1030|Y2=370|X3=1030|Y3=380|X4=1030|Y4=410
|RECORD=27|IndexInSheet=153|OwnerPartId=-1|LineWidth=1|Color=8388608|LocationCount=2|X1=980|Y1=380|X2=1030|Y2=380
|RECORD=27|IndexInSheet=154|OwnerPartId=-1|LineWidth=1|Color=8388608|LocationCount=4|X1=980|Y1=390|X2=1010|Y2=390|X3=1010|Y3=350|X4=1010|Y4=330
|RECORD=27|IndexInSheet=155|OwnerPartId=-1|LineWidth=1|Color=8388608|LocationCount=2|X1=1010|Y1=180|X2=1020|Y2=180
|RECORD=27|IndexInSheet=156|OwnerPartId=-1|LineWidth=1|Color=8388608|LocationCount=3|X1=1030|Y1=250|X2=1030|Y2=260|X3=1040|Y3=260
|RECORD=27|IndexInSheet=157|OwnerPartId=-1|LineWidth=1|Color=8388608|LocationCount=3|X1=1040|Y1=180|X2=1050|Y2=180|X3=1050|Y3=170
|RECORD=27|IndexInSheet=158|OwnerPartId=-1|LineWidth=1|Color=8388608|LocationCount=2|X1=1040|Y1=790|X2=1190|Y2=790
|RECORD=27|IndexInSheet=159|OwnerPartId=-1|LineWidth=1|Color=8388608|LocationCount=2|X1=1060|Y1=850|X2=1190|Y2=850
|RECORD=27|IndexInSheet=160|OwnerPartId=-1|LineWidth=1|Color=8388608|LocationCount=2|X1=1070|Y1=660|X2=1190|Y2=660
|RECORD=27|IndexInSheet=161|OwnerPartId=-1|LineWidth=1|Color=8388608|LocationCount=2|X1=1070|Y1=700|X2=1190|Y2=700
|RECORD=27|IndexInSheet=162|OwnerPartId=-1|LineWidth=1|Color=8388608|LocationCount=2|X1=1070|Y1=740|X2=1190|Y2=740
|RECORD=27|IndexInSheet=163|OwnerPartId=-1|LineWidth=1|Color=8388608|LocationCount=2|X1=1070|Y1=820|X2=1190|Y2=820
|RECORD=27|IndexInSheet=164|OwnerPartId=-1|LineWidth=1|Color=8388608|LocationCount=2|X1=1110|Y1=650|X2=1190|Y2=650
|RECORD=27|IndexInSheet=165|OwnerPartId=-1|LineWidth=1|Color=8388608|LocationCount=2|X1=1110|Y1=690|X2=1190|Y2=690
|RECORD=27|IndexInSheet=166|OwnerPartId=-1|LineWidth=1|Color=8388608|LocationCount=2|X1=1110|Y1=730|X2=1190|Y2=730
|RECORD=27|IndexInSheet=167|OwnerPartId=-1|LineWidth=1|Color=8388608|LocationCount=2|X1=1110|Y1=780|X2=1190|Y2=780
|RECORD=27|IndexInSheet=168|OwnerPartId=-1|LineWidth=1|Color=8388608|LocationCount=2|X1=1110|Y1=810|X2=1190|Y2=810
|RECORD=27|IndexInSheet=169|OwnerPartId=-1|LineWidth=1|Color=8388608|LocationCount=2|X1=1060|Y1=910|X2=1060|Y2=920
|RECORD=41|IndexInSheet=170|OwnerPartId=-1|Color=8388608|FontID=1|IsHidden=T|Name=ConfigurationParameters|ReadOnlyState=1
|RECORD=41|IndexInSheet=171|OwnerPartId=-1|Color=8388608|FontID=1|IsHidden=T|Name=ConfiguratorName|ReadOnlyState=1
|RECORD=41|IndexInSheet=172|OwnerPartId=-1|Color=8388608|FontID=1|IsHidden=T|Name=VersionControl_RevNumber|ReadOnlyState=1
|RECORD=41|IndexInSheet=173|OwnerPartId=-1|Color=8388608|FontID=1|IsHidden=T|Name=IsUserConfigurable|ReadOnlyState=1
|RECORD=41|IndexInSheet=174|OwnerPartId=-1|Color=8388608|FontID=1|IsHidden=T|Name=VersionControl_ProjFolderRevNumber|ReadOnlyState=1
|RECORD=41|IndexInSheet=175|OwnerPartId=-1|Color=8388608|FontID=1|IsHidden=T|Name=SPICEModelCache|ReadOnlyState=1
|RECORD=41|IndexInSheet=176|OwnerPartId=-1|Color=8388608|FontID=1|IsHidden=T|Text=*|Name=CurrentTime|ReadOnlyState=1
|RECORD=41|IndexInSheet=177|OwnerPartId=-1|Color=8388608|FontID=1|IsHidden=T|Text=*|Name=CurrentDate|ReadOnlyState=1
|RECORD=41|IndexInSheet=178|OwnerPartId=-1|Color=8388608|FontID=1|IsHidden=T|Text=*|Name=Time|ReadOnlyState=1
|RECORD=41|IndexInSheet=179|OwnerPartId=-1|Color=8388608|FontID=1|IsHidden=T|Text=*|Name=Date|ReadOnlyState=1
|RECORD=41|IndexInSheet=180|OwnerPartId=-1|Color=8388608|FontID=1|IsHidden=T|Text=*|Name=DocumentFullPathAndName|ReadOnlyState=1
|RECORD=41|IndexInSheet=181|OwnerPartId=-1|Color=8388608|FontID=1|IsHidden=T|Text=*|Name=DocumentName|ReadOnlyState=1
|RECORD=41|IndexInSheet=182|OwnerPartId=-1|Color=8388608|FontID=1|IsHidden=T|Text=*|Name=ModifiedDate|ReadOnlyState=1
|RECORD=41|IndexInSheet=183|OwnerPartId=-1|Color=8388608|FontID=1|IsHidden=T|Text=*|Name=ApprovedBy|ReadOnlyState=1
|RECORD=41|IndexInSheet=184|OwnerPartId=-1|Color=8388608|FontID=1|IsHidden=T|Text=*|Name=CheckedBy|ReadOnlyState=1
|RECORD=41|IndexInSheet=185|OwnerPartId=-1|Color=8388608|FontID=1|IsHidden=T|Text=*|Name=Author|ReadOnlyState=1
|RECORD=41|IndexInSheet=186|OwnerPartId=-1|Color=8388608|FontID=1|IsHidden=T|Text=*|Name=CompanyName|ReadOnlyState=1
|RECORD=41|IndexInSheet=187|OwnerPartId=-1|Color=8388608|FontID=1|IsHidden=T|Text=*|Name=DrawnBy|ReadOnlyState=1
|RECORD=41|IndexInSheet=188|OwnerPartId=-1|Color=8388608|FontID=1|IsHidden=T|Text=*|Name=Engineer|ReadOnlyState=1
|RECORD=41|IndexInSheet=189|OwnerPartId=-1|Color=8388608|FontID=1|IsHidden=T|Text=*|Name=Organization|ReadOnlyState=1
|RECORD=41|IndexInSheet=190|OwnerPartId=-1|Color=8388608|FontID=1|IsHidden=T|Text=*|Name=Address1|ReadOnlyState=1
|RECORD=41|IndexInSheet=191|OwnerPartId=-1|Color=8388608|FontID=1|IsHidden=T|Text=*|Name=Address2|ReadOnlyState=1
|RECORD=41|IndexInSheet=192|OwnerPartId=-1|Color=8388608|FontID=1|IsHidden=T|Text=*|Name=Address3|ReadOnlyState=1
|RECORD=41|IndexInSheet=193|OwnerPartId=-1|Color=8388608|FontID=1|IsHidden=T|Text=*|Name=Address4|ReadOnlyState=1
|RECORD=41|IndexInSheet=194|OwnerPartId=-1|Color=8388608|FontID=1|IsHidden=T|Text=*|Name=Title|ReadOnlyState=1
|RECORD=41|IndexInSheet=195|OwnerPartId=-1|Color=8388608|FontID=1|IsHidden=T|Text=*|Name=DocumentNumber|ReadOnlyState=1
|RECORD=41|IndexInSheet=196|OwnerPartId=-1|Color=8388608|FontID=1|IsHidden=T|Text=*|Name=Revision|ReadOnlyState=1
|RECORD=41|IndexInSheet=197|OwnerPartId=-1|Color=8388608|FontID=1|IsHidden=T|Text=*|Name=SheetNumber|ReadOnlyState=1
|RECORD=41|IndexInSheet=198|OwnerPartId=-1|Color=8388608|FontID=1|IsHidden=T|Text=*|Name=SheetTotal|ReadOnlyState=1
|RECORD=41|IndexInSheet=199|OwnerPartId=-1|Color=8388608|FontID=1|IsHidden=T|Text=*|Name=Rule|ReadOnlyState=1
|RECORD=41|IndexInSheet=200|OwnerPartId=-1|Color=8388608|FontID=1|IsHidden=T|Text=*|Name=ImagePath|ReadOnlyState=1
|RECORD=41|IndexInSheet=201|OwnerPartId=-1|Color=8388608|FontID=1|IsHidden=T|Text=*|Name=ProjectName|ReadOnlyState=1
|RECORD=41|IndexInSheet=202|OwnerPartId=-1|Color=8388608|FontID=1|IsHidden=T|Text=*|Name=Application_BuildNumber|ReadOnlyState=1
|RECORD=29|IndexInSheet=-1|OwnerPartId=-1|Location.X=670|Location.Y=940|Color=128
|RECORD=29|IndexInSheet=-1|OwnerPartId=-1|Location.X=670|Location.Y=950|Color=128
|RECORD=29|IndexInSheet=-1|OwnerPartId=-1|Location.X=740|Location.Y=630|Color=128
|RECORD=29|IndexInSheet=-1|OwnerPartId=-1|Location.X=740|Location.Y=660|Color=128
|RECORD=29|IndexInSheet=-1|OwnerPartId=-1|Location.X=740|Location.Y=690|Color=128
|RECORD=29|IndexInSheet=-1|OwnerPartId=-1|Location.X=740|Location.Y=700|Color=128
|RECORD=29|IndexInSheet=-1|OwnerPartId=-1|Location.X=740|Location.Y=730|Color=128
|RECORD=29|IndexInSheet=-1|OwnerPartId=-1|Location.X=740|Location.Y=740|Color=128
|RECORD=29|IndexInSheet=-1|OwnerPartId=-1|Location.X=740|Location.Y=770|Color=128
|RECORD=29|IndexInSheet=-1|OwnerPartId=-1|Location.X=740|Location.Y=790|Color=128
|RECORD=29|IndexInSheet=-1|OwnerPartId=-1|Location.X=740|Location.Y=820|Color=128
|RECORD=29|IndexInSheet=-1|OwnerPartId=-1|Location.X=740|Location.Y=890|Color=128
|RECORD=29|IndexInSheet=-1|OwnerPartId=-1|Location.X=940|Location.Y=640|Color=128
|RECORD=29|IndexInSheet=-1|OwnerPartId=-1|Location.X=940|Location.Y=670|Color=128
|RECORD=29|IndexInSheet=-1|OwnerPartId=-1|Location.X=940|Location.Y=680|Color=128
|RECORD=29|IndexInSheet=-1|OwnerPartId=-1|Location.X=940|Location.Y=710|Color=128
|RECORD=29|IndexInSheet=-1|OwnerPartId=-1|Location.X=940|Location.Y=720|Color=128
|RECORD=29|IndexInSheet=-1|OwnerPartId=-1|Location.X=940|Location.Y=750|Color=128
|RECORD=29|IndexInSheet=-1|OwnerPartId=-1|Location.X=940|Location.Y=770|Color=128
|RECORD=29|IndexInSheet=-1|OwnerPartId=-1|Location.X=940|Location.Y=800|Color=128
|RECORD=29|IndexInSheet=-1|OwnerPartId=-1|Location.X=940|Location.Y=830|Color=128
|RECORD=29|IndexInSheet=-1|OwnerPartId=-1|Location.X=990|Location.Y=940|Color=128
|RECORD=29|IndexInSheet=-1|OwnerPartId=-1|Location.X=1010|Location.Y=350|Color=128
|RECORD=29|IndexInSheet=-1|OwnerPartId=-1|Location.X=1030|Location.Y=380|Color=128
|RECORD=29|IndexInSheet=-1|OwnerPartId=-1|Location.X=1030|Location.Y=870|Color=128
|RECORD=29|IndexInSheet=-1|OwnerPartId=-1|Location.X=1060|Location.Y=850|Color=128